FILE_TYPE = MACRO_DRAWING;
SET COLOR_WIRE YELLOW;
SET COLOR_PROP ORANGE;
SET COLOR_DOT WHITE;
SET COLOR_ARC YELLOW;
SET COLOR_BODY GREEN;
SET COLOR_NOTE PURPLE;
SET PROP_DISPLAY VALUE;
SET PAGE_NUMBER P102;
FORCEADD OFFPAGE..5
(-8425 2125);
FORCEPROP 2 LAST $XR0 42 
J 0
(-8649 2125);
DISPLAY 0.638298 (-8649 2125);
PAINT MONO (-8649 2125);
FORCEPROP 2 LAST PATH I1
J 0
(-8625 2175);
DISPLAY 1.021277 (-8625 2175);
DISPLAY INVISIBLE (-8625 2175);
FORCEPROP 1 LAST COMMENT_BODY TRUE
J 0
(-8325 2050);
DISPLAY 0.872340 (-8325 2050);
PAINT GREEN (-8325 2050);
DISPLAY INVISIBLE (-8325 2050);
FORCEPROP 1 LAST OFFPAGE TRUE
J 0
(-8100 2000);
DISPLAY 0.872340 (-8100 2000);
PAINT GREEN (-8100 2000);
DISPLAY INVISIBLE (-8100 2000);
FORCEPROP 2 LAST CDS_LIB mstr_standard
J 0
(-8425 2125);
DISPLAY 0.808511 (-8425 2125);
DISPLAY INVISIBLE (-8425 2125);
FORCEADD OFFPAGE..6
(-8425 3725);
FORCEPROP 2 LAST $XR0 42 
J 0
(-8674 3725);
DISPLAY 0.638298 (-8674 3725);
PAINT MONO (-8674 3725);
FORCEPROP 2 LAST PATH I10
J 0
(-8650 3775);
DISPLAY 1.021277 (-8650 3775);
DISPLAY INVISIBLE (-8650 3775);
FORCEPROP 1 LAST COMMENT_BODY TRUE
J 0
(-8325 3650);
DISPLAY 0.872340 (-8325 3650);
PAINT GREEN (-8325 3650);
DISPLAY INVISIBLE (-8325 3650);
FORCEPROP 1 LAST OFFPAGE TRUE
J 0
(-8100 3600);
DISPLAY 0.872340 (-8100 3600);
PAINT GREEN (-8100 3600);
DISPLAY INVISIBLE (-8100 3600);
FORCEPROP 2 LAST CDS_LIB mstr_standard
J 0
(-8425 3725);
DISPLAY 0.723404 (-8425 3725);
PAINT MONO (-8425 3725);
DISPLAY INVISIBLE (-8425 3725);
FORCEADD TAP..1
(-6125 4325);
FORCEPROP 3 LASTPIN (-6175 4325) SIG_NAME M_F_CPU1_SA_DQ<7>
J 0
(-6165 4335);
DISPLAY 0.659574 (-6165 4335);
PAINT MONO (-6165 4335);
DISPLAY INVISIBLE (-6165 4335);
FORCEPROP 1 LASTPIN (-6175 4325) BN 7
J 0
(-6187 4333);
DISPLAY 0.489362 (-6187 4333);
PAINT GREEN (-6187 4333);
FORCEPROP 2 LAST CDS_LIB mstr_standard
J 0
(-6125 4325);
DISPLAY 0.723404 (-6125 4325);
PAINT MONO (-6125 4325);
DISPLAY INVISIBLE (-6125 4325);
FORCEPROP 1 LAST BODY_TYPE PLUMBING
J 0
(-6125 4375);
DISPLAY 0.872340 (-6125 4375);
PAINT GREEN (-6125 4375);
DISPLAY INVISIBLE (-6125 4375);
FORCEPROP 1 LAST HDL_TAP TRUE
J 0
(-5800 4200);
DISPLAY 0.872340 (-5800 4200);
DISPLAY INVISIBLE (-5800 4200);
FORCEPROP 1 LAST PATH I100
J 0
(-6127 4325);
DISPLAY 0.872340 (-6127 4325);
PAINT GREEN (-6127 4325);
DISPLAY INVISIBLE (-6127 4325);
FORCEADD TAP..1
(-6125 4275);
FORCEPROP 3 LASTPIN (-6175 4275) SIG_NAME M_F_CPU1_SA_DQ<6>
J 0
(-6165 4285);
DISPLAY 0.659574 (-6165 4285);
PAINT MONO (-6165 4285);
DISPLAY INVISIBLE (-6165 4285);
FORCEPROP 1 LASTPIN (-6175 4275) BN 6
J 0
(-6187 4283);
DISPLAY 0.489362 (-6187 4283);
PAINT GREEN (-6187 4283);
FORCEPROP 2 LAST CDS_LIB mstr_standard
J 0
(-6125 4275);
DISPLAY 0.723404 (-6125 4275);
PAINT MONO (-6125 4275);
DISPLAY INVISIBLE (-6125 4275);
FORCEPROP 1 LAST BODY_TYPE PLUMBING
J 0
(-6125 4325);
DISPLAY 0.872340 (-6125 4325);
PAINT GREEN (-6125 4325);
DISPLAY INVISIBLE (-6125 4325);
FORCEPROP 1 LAST HDL_TAP TRUE
J 0
(-5800 4150);
DISPLAY 0.872340 (-5800 4150);
DISPLAY INVISIBLE (-5800 4150);
FORCEPROP 1 LAST PATH I101
J 0
(-6127 4275);
DISPLAY 0.872340 (-6127 4275);
PAINT GREEN (-6127 4275);
DISPLAY INVISIBLE (-6127 4275);
FORCEADD TAP..1
(-6125 4375);
FORCEPROP 3 LASTPIN (-6175 4375) SIG_NAME M_F_CPU1_SA_DQ<8>
J 0
(-6165 4385);
DISPLAY 0.659574 (-6165 4385);
PAINT MONO (-6165 4385);
DISPLAY INVISIBLE (-6165 4385);
FORCEPROP 1 LASTPIN (-6175 4375) BN 8
J 0
(-6187 4383);
DISPLAY 0.489362 (-6187 4383);
PAINT GREEN (-6187 4383);
FORCEPROP 2 LAST CDS_LIB mstr_standard
J 0
(-6125 4375);
DISPLAY 0.723404 (-6125 4375);
PAINT MONO (-6125 4375);
DISPLAY INVISIBLE (-6125 4375);
FORCEPROP 1 LAST BODY_TYPE PLUMBING
J 0
(-6125 4425);
DISPLAY 0.872340 (-6125 4425);
PAINT GREEN (-6125 4425);
DISPLAY INVISIBLE (-6125 4425);
FORCEPROP 1 LAST HDL_TAP TRUE
J 0
(-5800 4250);
DISPLAY 0.872340 (-5800 4250);
DISPLAY INVISIBLE (-5800 4250);
FORCEPROP 1 LAST PATH I102
J 0
(-6127 4375);
DISPLAY 0.872340 (-6127 4375);
PAINT GREEN (-6127 4375);
DISPLAY INVISIBLE (-6127 4375);
FORCEADD TAP..1
(-6125 4425);
FORCEPROP 3 LASTPIN (-6175 4425) SIG_NAME M_F_CPU1_SA_DQ<9>
J 0
(-6165 4435);
DISPLAY 0.659574 (-6165 4435);
PAINT MONO (-6165 4435);
DISPLAY INVISIBLE (-6165 4435);
FORCEPROP 1 LASTPIN (-6175 4425) BN 9
J 0
(-6187 4433);
DISPLAY 0.489362 (-6187 4433);
PAINT GREEN (-6187 4433);
FORCEPROP 2 LAST CDS_LIB mstr_standard
J 0
(-6125 4425);
DISPLAY 0.723404 (-6125 4425);
PAINT MONO (-6125 4425);
DISPLAY INVISIBLE (-6125 4425);
FORCEPROP 1 LAST BODY_TYPE PLUMBING
J 0
(-6125 4475);
DISPLAY 0.872340 (-6125 4475);
PAINT GREEN (-6125 4475);
DISPLAY INVISIBLE (-6125 4475);
FORCEPROP 1 LAST HDL_TAP TRUE
J 0
(-5800 4300);
DISPLAY 0.872340 (-5800 4300);
DISPLAY INVISIBLE (-5800 4300);
FORCEPROP 1 LAST PATH I103
J 0
(-6127 4425);
DISPLAY 0.872340 (-6127 4425);
PAINT GREEN (-6127 4425);
DISPLAY INVISIBLE (-6127 4425);
FORCEADD TAP..1
(-6125 4525);
FORCEPROP 3 LASTPIN (-6175 4525) SIG_NAME M_F_CPU1_SA_DQ<11>
J 0
(-6165 4535);
DISPLAY 0.659574 (-6165 4535);
PAINT MONO (-6165 4535);
DISPLAY INVISIBLE (-6165 4535);
FORCEPROP 1 LASTPIN (-6175 4525) BN 11
J 0
(-6187 4533);
DISPLAY 0.489362 (-6187 4533);
PAINT GREEN (-6187 4533);
FORCEPROP 2 LAST CDS_LIB mstr_standard
J 0
(-6125 4525);
DISPLAY 0.723404 (-6125 4525);
PAINT MONO (-6125 4525);
DISPLAY INVISIBLE (-6125 4525);
FORCEPROP 1 LAST BODY_TYPE PLUMBING
J 0
(-6125 4575);
DISPLAY 0.872340 (-6125 4575);
PAINT GREEN (-6125 4575);
DISPLAY INVISIBLE (-6125 4575);
FORCEPROP 1 LAST HDL_TAP TRUE
J 0
(-5800 4400);
DISPLAY 0.872340 (-5800 4400);
DISPLAY INVISIBLE (-5800 4400);
FORCEPROP 1 LAST PATH I104
J 0
(-6127 4525);
DISPLAY 0.872340 (-6127 4525);
PAINT GREEN (-6127 4525);
DISPLAY INVISIBLE (-6127 4525);
FORCEADD TAP..1
(-6125 4575);
FORCEPROP 3 LASTPIN (-6175 4575) SIG_NAME M_F_CPU1_SA_DQ<12>
J 0
(-6165 4585);
DISPLAY 0.659574 (-6165 4585);
PAINT MONO (-6165 4585);
DISPLAY INVISIBLE (-6165 4585);
FORCEPROP 1 LASTPIN (-6175 4575) BN 12
J 0
(-6187 4583);
DISPLAY 0.489362 (-6187 4583);
PAINT GREEN (-6187 4583);
FORCEPROP 2 LAST CDS_LIB mstr_standard
J 0
(-6125 4575);
DISPLAY 0.723404 (-6125 4575);
PAINT MONO (-6125 4575);
DISPLAY INVISIBLE (-6125 4575);
FORCEPROP 1 LAST BODY_TYPE PLUMBING
J 0
(-6125 4625);
DISPLAY 0.872340 (-6125 4625);
PAINT GREEN (-6125 4625);
DISPLAY INVISIBLE (-6125 4625);
FORCEPROP 1 LAST HDL_TAP TRUE
J 0
(-5800 4450);
DISPLAY 0.872340 (-5800 4450);
DISPLAY INVISIBLE (-5800 4450);
FORCEPROP 1 LAST PATH I105
J 0
(-6127 4575);
DISPLAY 0.872340 (-6127 4575);
PAINT GREEN (-6127 4575);
DISPLAY INVISIBLE (-6127 4575);
FORCEADD TAP..1
(-6125 4625);
FORCEPROP 3 LASTPIN (-6175 4625) SIG_NAME M_F_CPU1_SA_DQ<13>
J 0
(-6165 4635);
DISPLAY 0.659574 (-6165 4635);
PAINT MONO (-6165 4635);
DISPLAY INVISIBLE (-6165 4635);
FORCEPROP 1 LASTPIN (-6175 4625) BN 13
J 0
(-6187 4633);
DISPLAY 0.489362 (-6187 4633);
PAINT GREEN (-6187 4633);
FORCEPROP 2 LAST CDS_LIB mstr_standard
J 0
(-6125 4625);
DISPLAY 0.723404 (-6125 4625);
PAINT MONO (-6125 4625);
DISPLAY INVISIBLE (-6125 4625);
FORCEPROP 1 LAST BODY_TYPE PLUMBING
J 0
(-6125 4675);
DISPLAY 0.872340 (-6125 4675);
PAINT GREEN (-6125 4675);
DISPLAY INVISIBLE (-6125 4675);
FORCEPROP 1 LAST HDL_TAP TRUE
J 0
(-5800 4500);
DISPLAY 0.872340 (-5800 4500);
DISPLAY INVISIBLE (-5800 4500);
FORCEPROP 1 LAST PATH I106
J 0
(-6127 4625);
DISPLAY 0.872340 (-6127 4625);
PAINT GREEN (-6127 4625);
DISPLAY INVISIBLE (-6127 4625);
FORCEADD TAP..1
(-6125 4675);
FORCEPROP 3 LASTPIN (-6175 4675) SIG_NAME M_F_CPU1_SA_DQ<14>
J 0
(-6165 4685);
DISPLAY 0.659574 (-6165 4685);
PAINT MONO (-6165 4685);
DISPLAY INVISIBLE (-6165 4685);
FORCEPROP 1 LASTPIN (-6175 4675) BN 14
J 0
(-6187 4683);
DISPLAY 0.489362 (-6187 4683);
PAINT GREEN (-6187 4683);
FORCEPROP 2 LAST CDS_LIB mstr_standard
J 0
(-6125 4675);
DISPLAY 0.723404 (-6125 4675);
PAINT MONO (-6125 4675);
DISPLAY INVISIBLE (-6125 4675);
FORCEPROP 1 LAST BODY_TYPE PLUMBING
J 0
(-6125 4725);
DISPLAY 0.872340 (-6125 4725);
PAINT GREEN (-6125 4725);
DISPLAY INVISIBLE (-6125 4725);
FORCEPROP 1 LAST HDL_TAP TRUE
J 0
(-5800 4550);
DISPLAY 0.872340 (-5800 4550);
DISPLAY INVISIBLE (-5800 4550);
FORCEPROP 1 LAST PATH I107
J 0
(-6127 4675);
DISPLAY 0.872340 (-6127 4675);
PAINT GREEN (-6127 4675);
DISPLAY INVISIBLE (-6127 4675);
FORCEADD TAP..1
(-6125 4475);
FORCEPROP 3 LASTPIN (-6175 4475) SIG_NAME M_F_CPU1_SA_DQ<10>
J 0
(-6165 4485);
DISPLAY 0.659574 (-6165 4485);
PAINT MONO (-6165 4485);
DISPLAY INVISIBLE (-6165 4485);
FORCEPROP 1 LASTPIN (-6175 4475) BN 10
J 0
(-6187 4483);
DISPLAY 0.489362 (-6187 4483);
PAINT GREEN (-6187 4483);
FORCEPROP 2 LAST CDS_LIB mstr_standard
J 0
(-6125 4475);
DISPLAY 0.723404 (-6125 4475);
PAINT MONO (-6125 4475);
DISPLAY INVISIBLE (-6125 4475);
FORCEPROP 1 LAST BODY_TYPE PLUMBING
J 0
(-6125 4525);
DISPLAY 0.872340 (-6125 4525);
PAINT GREEN (-6125 4525);
DISPLAY INVISIBLE (-6125 4525);
FORCEPROP 1 LAST HDL_TAP TRUE
J 0
(-5800 4350);
DISPLAY 0.872340 (-5800 4350);
DISPLAY INVISIBLE (-5800 4350);
FORCEPROP 1 LAST PATH I108
J 0
(-6127 4475);
DISPLAY 0.872340 (-6127 4475);
PAINT GREEN (-6127 4475);
DISPLAY INVISIBLE (-6127 4475);
FORCEADD TAP..1
(-6125 4925);
FORCEPROP 3 LASTPIN (-6175 4925) SIG_NAME M_F_CPU1_SA_DQ<19>
J 0
(-6165 4935);
DISPLAY 0.659574 (-6165 4935);
PAINT MONO (-6165 4935);
DISPLAY INVISIBLE (-6165 4935);
FORCEPROP 1 LASTPIN (-6175 4925) BN 19
J 0
(-6187 4933);
DISPLAY 0.489362 (-6187 4933);
PAINT GREEN (-6187 4933);
FORCEPROP 2 LAST CDS_LIB mstr_standard
J 0
(-6125 4925);
DISPLAY 0.723404 (-6125 4925);
PAINT MONO (-6125 4925);
DISPLAY INVISIBLE (-6125 4925);
FORCEPROP 1 LAST BODY_TYPE PLUMBING
J 0
(-6125 4975);
DISPLAY 0.872340 (-6125 4975);
PAINT GREEN (-6125 4975);
DISPLAY INVISIBLE (-6125 4975);
FORCEPROP 1 LAST HDL_TAP TRUE
J 0
(-5800 4800);
DISPLAY 0.872340 (-5800 4800);
DISPLAY INVISIBLE (-5800 4800);
FORCEPROP 1 LAST PATH I109
J 0
(-6127 4925);
DISPLAY 0.872340 (-6127 4925);
PAINT GREEN (-6127 4925);
DISPLAY INVISIBLE (-6127 4925);
FORCEADD OFFPAGE..6
(-8425 4175);
FORCEPROP 2 LAST $XR0 42 
J 0
(-8674 4175);
DISPLAY 0.638298 (-8674 4175);
PAINT MONO (-8674 4175);
FORCEPROP 2 LAST PATH I11
J 0
(-8650 4225);
DISPLAY 1.021277 (-8650 4225);
DISPLAY INVISIBLE (-8650 4225);
FORCEPROP 1 LAST COMMENT_BODY TRUE
J 0
(-8325 4100);
DISPLAY 0.872340 (-8325 4100);
PAINT GREEN (-8325 4100);
DISPLAY INVISIBLE (-8325 4100);
FORCEPROP 1 LAST OFFPAGE TRUE
J 0
(-8100 4050);
DISPLAY 0.872340 (-8100 4050);
PAINT GREEN (-8100 4050);
DISPLAY INVISIBLE (-8100 4050);
FORCEPROP 2 LAST CDS_LIB mstr_standard
J 0
(-8425 4175);
DISPLAY 0.723404 (-8425 4175);
PAINT MONO (-8425 4175);
DISPLAY INVISIBLE (-8425 4175);
FORCEADD TAP..1
(-6125 4775);
FORCEPROP 3 LASTPIN (-6175 4775) SIG_NAME M_F_CPU1_SA_DQ<16>
J 0
(-6165 4785);
DISPLAY 0.659574 (-6165 4785);
PAINT MONO (-6165 4785);
DISPLAY INVISIBLE (-6165 4785);
FORCEPROP 1 LASTPIN (-6175 4775) BN 16
J 0
(-6187 4783);
DISPLAY 0.489362 (-6187 4783);
PAINT GREEN (-6187 4783);
FORCEPROP 2 LAST CDS_LIB mstr_standard
J 0
(-6125 4775);
DISPLAY 0.723404 (-6125 4775);
PAINT MONO (-6125 4775);
DISPLAY INVISIBLE (-6125 4775);
FORCEPROP 1 LAST BODY_TYPE PLUMBING
J 0
(-6125 4825);
DISPLAY 0.872340 (-6125 4825);
PAINT GREEN (-6125 4825);
DISPLAY INVISIBLE (-6125 4825);
FORCEPROP 1 LAST HDL_TAP TRUE
J 0
(-5800 4650);
DISPLAY 0.872340 (-5800 4650);
DISPLAY INVISIBLE (-5800 4650);
FORCEPROP 1 LAST PATH I110
J 0
(-6127 4775);
DISPLAY 0.872340 (-6127 4775);
PAINT GREEN (-6127 4775);
DISPLAY INVISIBLE (-6127 4775);
FORCEADD TAP..1
(-6125 4875);
FORCEPROP 3 LASTPIN (-6175 4875) SIG_NAME M_F_CPU1_SA_DQ<18>
J 0
(-6165 4885);
DISPLAY 0.659574 (-6165 4885);
PAINT MONO (-6165 4885);
DISPLAY INVISIBLE (-6165 4885);
FORCEPROP 1 LASTPIN (-6175 4875) BN 18
J 0
(-6187 4883);
DISPLAY 0.489362 (-6187 4883);
PAINT GREEN (-6187 4883);
FORCEPROP 2 LAST CDS_LIB mstr_standard
J 0
(-6125 4875);
DISPLAY 0.723404 (-6125 4875);
PAINT MONO (-6125 4875);
DISPLAY INVISIBLE (-6125 4875);
FORCEPROP 1 LAST BODY_TYPE PLUMBING
J 0
(-6125 4925);
DISPLAY 0.872340 (-6125 4925);
PAINT GREEN (-6125 4925);
DISPLAY INVISIBLE (-6125 4925);
FORCEPROP 1 LAST HDL_TAP TRUE
J 0
(-5800 4750);
DISPLAY 0.872340 (-5800 4750);
DISPLAY INVISIBLE (-5800 4750);
FORCEPROP 1 LAST PATH I111
J 0
(-6127 4875);
DISPLAY 0.872340 (-6127 4875);
PAINT GREEN (-6127 4875);
DISPLAY INVISIBLE (-6127 4875);
FORCEADD TAP..1
(-6125 4825);
FORCEPROP 3 LASTPIN (-6175 4825) SIG_NAME M_F_CPU1_SA_DQ<17>
J 0
(-6165 4835);
DISPLAY 0.659574 (-6165 4835);
PAINT MONO (-6165 4835);
DISPLAY INVISIBLE (-6165 4835);
FORCEPROP 1 LASTPIN (-6175 4825) BN 17
J 0
(-6187 4833);
DISPLAY 0.489362 (-6187 4833);
PAINT GREEN (-6187 4833);
FORCEPROP 2 LAST CDS_LIB mstr_standard
J 0
(-6125 4825);
DISPLAY 0.723404 (-6125 4825);
PAINT MONO (-6125 4825);
DISPLAY INVISIBLE (-6125 4825);
FORCEPROP 1 LAST BODY_TYPE PLUMBING
J 0
(-6125 4875);
DISPLAY 0.872340 (-6125 4875);
PAINT GREEN (-6125 4875);
DISPLAY INVISIBLE (-6125 4875);
FORCEPROP 1 LAST HDL_TAP TRUE
J 0
(-5800 4700);
DISPLAY 0.872340 (-5800 4700);
DISPLAY INVISIBLE (-5800 4700);
FORCEPROP 1 LAST PATH I112
J 0
(-6127 4825);
DISPLAY 0.872340 (-6127 4825);
PAINT GREEN (-6127 4825);
DISPLAY INVISIBLE (-6127 4825);
FORCEADD TAP..1
(-6125 4725);
FORCEPROP 3 LASTPIN (-6175 4725) SIG_NAME M_F_CPU1_SA_DQ<15>
J 0
(-6165 4735);
DISPLAY 0.659574 (-6165 4735);
PAINT MONO (-6165 4735);
DISPLAY INVISIBLE (-6165 4735);
FORCEPROP 1 LASTPIN (-6175 4725) BN 15
J 0
(-6187 4733);
DISPLAY 0.489362 (-6187 4733);
PAINT GREEN (-6187 4733);
FORCEPROP 2 LAST CDS_LIB mstr_standard
J 0
(-6125 4725);
DISPLAY 0.723404 (-6125 4725);
PAINT MONO (-6125 4725);
DISPLAY INVISIBLE (-6125 4725);
FORCEPROP 1 LAST BODY_TYPE PLUMBING
J 0
(-6125 4775);
DISPLAY 0.872340 (-6125 4775);
PAINT GREEN (-6125 4775);
DISPLAY INVISIBLE (-6125 4775);
FORCEPROP 1 LAST HDL_TAP TRUE
J 0
(-5800 4600);
DISPLAY 0.872340 (-5800 4600);
DISPLAY INVISIBLE (-5800 4600);
FORCEPROP 1 LAST PATH I113
J 0
(-6127 4725);
DISPLAY 0.872340 (-6127 4725);
PAINT GREEN (-6127 4725);
DISPLAY INVISIBLE (-6127 4725);
FORCEADD TAP..1
(-6125 4975);
FORCEPROP 3 LASTPIN (-6175 4975) SIG_NAME M_F_CPU1_SA_DQ<20>
J 0
(-6165 4985);
DISPLAY 0.659574 (-6165 4985);
PAINT MONO (-6165 4985);
DISPLAY INVISIBLE (-6165 4985);
FORCEPROP 1 LASTPIN (-6175 4975) BN 20
J 0
(-6187 4983);
DISPLAY 0.489362 (-6187 4983);
PAINT GREEN (-6187 4983);
FORCEPROP 2 LAST CDS_LIB mstr_standard
J 0
(-6125 4975);
DISPLAY 0.723404 (-6125 4975);
PAINT MONO (-6125 4975);
DISPLAY INVISIBLE (-6125 4975);
FORCEPROP 1 LAST BODY_TYPE PLUMBING
J 0
(-6125 5025);
DISPLAY 0.872340 (-6125 5025);
PAINT GREEN (-6125 5025);
DISPLAY INVISIBLE (-6125 5025);
FORCEPROP 1 LAST HDL_TAP TRUE
J 0
(-5800 4850);
DISPLAY 0.872340 (-5800 4850);
DISPLAY INVISIBLE (-5800 4850);
FORCEPROP 1 LAST PATH I114
J 0
(-6127 4975);
DISPLAY 0.872340 (-6127 4975);
PAINT GREEN (-6127 4975);
DISPLAY INVISIBLE (-6127 4975);
FORCEADD TAP..1
(-6125 5025);
FORCEPROP 3 LASTPIN (-6175 5025) SIG_NAME M_F_CPU1_SA_DQ<21>
J 0
(-6165 5035);
DISPLAY 0.659574 (-6165 5035);
PAINT MONO (-6165 5035);
DISPLAY INVISIBLE (-6165 5035);
FORCEPROP 1 LASTPIN (-6175 5025) BN 21
J 0
(-6187 5033);
DISPLAY 0.489362 (-6187 5033);
PAINT GREEN (-6187 5033);
FORCEPROP 2 LAST CDS_LIB mstr_standard
J 0
(-6125 5025);
DISPLAY 0.723404 (-6125 5025);
PAINT MONO (-6125 5025);
DISPLAY INVISIBLE (-6125 5025);
FORCEPROP 1 LAST BODY_TYPE PLUMBING
J 0
(-6125 5075);
DISPLAY 0.872340 (-6125 5075);
PAINT GREEN (-6125 5075);
DISPLAY INVISIBLE (-6125 5075);
FORCEPROP 1 LAST HDL_TAP TRUE
J 0
(-5800 4900);
DISPLAY 0.872340 (-5800 4900);
DISPLAY INVISIBLE (-5800 4900);
FORCEPROP 1 LAST PATH I115
J 0
(-6127 5025);
DISPLAY 0.872340 (-6127 5025);
PAINT GREEN (-6127 5025);
DISPLAY INVISIBLE (-6127 5025);
FORCEADD TAP..1
(-6125 5075);
FORCEPROP 3 LASTPIN (-6175 5075) SIG_NAME M_F_CPU1_SA_DQ<22>
J 0
(-6165 5085);
DISPLAY 0.659574 (-6165 5085);
PAINT MONO (-6165 5085);
DISPLAY INVISIBLE (-6165 5085);
FORCEPROP 1 LASTPIN (-6175 5075) BN 22
J 0
(-6187 5083);
DISPLAY 0.489362 (-6187 5083);
PAINT GREEN (-6187 5083);
FORCEPROP 2 LAST CDS_LIB mstr_standard
J 0
(-6125 5075);
DISPLAY 0.723404 (-6125 5075);
PAINT MONO (-6125 5075);
DISPLAY INVISIBLE (-6125 5075);
FORCEPROP 1 LAST BODY_TYPE PLUMBING
J 0
(-6125 5125);
DISPLAY 0.872340 (-6125 5125);
PAINT GREEN (-6125 5125);
DISPLAY INVISIBLE (-6125 5125);
FORCEPROP 1 LAST HDL_TAP TRUE
J 0
(-5800 4950);
DISPLAY 0.872340 (-5800 4950);
DISPLAY INVISIBLE (-5800 4950);
FORCEPROP 1 LAST PATH I116
J 0
(-6127 5075);
DISPLAY 0.872340 (-6127 5075);
PAINT GREEN (-6127 5075);
DISPLAY INVISIBLE (-6127 5075);
FORCEADD TAP..1
(-6125 5225);
FORCEPROP 3 LASTPIN (-6175 5225) SIG_NAME M_F_CPU1_SA_DQ<25>
J 0
(-6165 5235);
DISPLAY 0.659574 (-6165 5235);
PAINT MONO (-6165 5235);
DISPLAY INVISIBLE (-6165 5235);
FORCEPROP 1 LASTPIN (-6175 5225) BN 25
J 0
(-6187 5233);
DISPLAY 0.489362 (-6187 5233);
PAINT GREEN (-6187 5233);
FORCEPROP 2 LAST CDS_LIB mstr_standard
J 0
(-6125 5225);
DISPLAY 0.723404 (-6125 5225);
PAINT MONO (-6125 5225);
DISPLAY INVISIBLE (-6125 5225);
FORCEPROP 1 LAST BODY_TYPE PLUMBING
J 0
(-6125 5275);
DISPLAY 0.872340 (-6125 5275);
PAINT GREEN (-6125 5275);
DISPLAY INVISIBLE (-6125 5275);
FORCEPROP 1 LAST HDL_TAP TRUE
J 0
(-5800 5100);
DISPLAY 0.872340 (-5800 5100);
DISPLAY INVISIBLE (-5800 5100);
FORCEPROP 1 LAST PATH I117
J 0
(-6127 5225);
DISPLAY 0.872340 (-6127 5225);
PAINT GREEN (-6127 5225);
DISPLAY INVISIBLE (-6127 5225);
FORCEADD TAP..1
(-6125 5125);
FORCEPROP 3 LASTPIN (-6175 5125) SIG_NAME M_F_CPU1_SA_DQ<23>
J 0
(-6165 5135);
DISPLAY 0.659574 (-6165 5135);
PAINT MONO (-6165 5135);
DISPLAY INVISIBLE (-6165 5135);
FORCEPROP 1 LASTPIN (-6175 5125) BN 23
J 0
(-6187 5133);
DISPLAY 0.489362 (-6187 5133);
PAINT GREEN (-6187 5133);
FORCEPROP 2 LAST CDS_LIB mstr_standard
J 0
(-6125 5125);
DISPLAY 0.723404 (-6125 5125);
PAINT MONO (-6125 5125);
DISPLAY INVISIBLE (-6125 5125);
FORCEPROP 1 LAST BODY_TYPE PLUMBING
J 0
(-6125 5175);
DISPLAY 0.872340 (-6125 5175);
PAINT GREEN (-6125 5175);
DISPLAY INVISIBLE (-6125 5175);
FORCEPROP 1 LAST HDL_TAP TRUE
J 0
(-5800 5000);
DISPLAY 0.872340 (-5800 5000);
DISPLAY INVISIBLE (-5800 5000);
FORCEPROP 1 LAST PATH I118
J 0
(-6127 5125);
DISPLAY 0.872340 (-6127 5125);
PAINT GREEN (-6127 5125);
DISPLAY INVISIBLE (-6127 5125);
FORCEADD TAP..1
(-6125 5175);
FORCEPROP 3 LASTPIN (-6175 5175) SIG_NAME M_F_CPU1_SA_DQ<24>
J 0
(-6165 5185);
DISPLAY 0.659574 (-6165 5185);
PAINT MONO (-6165 5185);
DISPLAY INVISIBLE (-6165 5185);
FORCEPROP 1 LASTPIN (-6175 5175) BN 24
J 0
(-6187 5183);
DISPLAY 0.489362 (-6187 5183);
PAINT GREEN (-6187 5183);
FORCEPROP 2 LAST CDS_LIB mstr_standard
J 0
(-6125 5175);
DISPLAY 0.723404 (-6125 5175);
PAINT MONO (-6125 5175);
DISPLAY INVISIBLE (-6125 5175);
FORCEPROP 1 LAST BODY_TYPE PLUMBING
J 0
(-6125 5225);
DISPLAY 0.872340 (-6125 5225);
PAINT GREEN (-6125 5225);
DISPLAY INVISIBLE (-6125 5225);
FORCEPROP 1 LAST HDL_TAP TRUE
J 0
(-5800 5050);
DISPLAY 0.872340 (-5800 5050);
DISPLAY INVISIBLE (-5800 5050);
FORCEPROP 1 LAST PATH I119
J 0
(-6127 5175);
DISPLAY 0.872340 (-6127 5175);
PAINT GREEN (-6127 5175);
DISPLAY INVISIBLE (-6127 5175);
FORCEADD OFFPAGE..1
(-8425 4225);
FORCEPROP 2 LAST $XR0 42 
J 0
(-8646 4225);
DISPLAY 0.638298 (-8646 4225);
PAINT MONO (-8646 4225);
FORCEPROP 2 LAST PATH I12
J 0
(-8675 4275);
DISPLAY 1.021277 (-8675 4275);
DISPLAY INVISIBLE (-8675 4275);
FORCEPROP 1 LAST COMMENT_BODY TRUE
J 0
(-8300 4125);
DISPLAY 0.872340 (-8300 4125);
PAINT GREEN (-8300 4125);
DISPLAY INVISIBLE (-8300 4125);
FORCEPROP 1 LAST OFFPAGE TRUE
J 0
(-8100 4100);
DISPLAY 0.872340 (-8100 4100);
PAINT GREEN (-8100 4100);
DISPLAY INVISIBLE (-8100 4100);
FORCEPROP 2 LAST CDS_LIB mstr_standard
J 0
(-8425 4225);
DISPLAY 0.808511 (-8425 4225);
DISPLAY INVISIBLE (-8425 4225);
FORCEADD TAP..1
(-6125 5425);
FORCEPROP 3 LASTPIN (-6175 5425) SIG_NAME M_F_CPU1_SA_DQ<29>
J 0
(-6165 5435);
DISPLAY 0.659574 (-6165 5435);
PAINT MONO (-6165 5435);
DISPLAY INVISIBLE (-6165 5435);
FORCEPROP 1 LASTPIN (-6175 5425) BN 29
J 0
(-6187 5433);
DISPLAY 0.489362 (-6187 5433);
PAINT GREEN (-6187 5433);
FORCEPROP 2 LAST CDS_LIB mstr_standard
J 0
(-6125 5425);
DISPLAY 0.723404 (-6125 5425);
PAINT MONO (-6125 5425);
DISPLAY INVISIBLE (-6125 5425);
FORCEPROP 1 LAST BODY_TYPE PLUMBING
J 0
(-6125 5475);
DISPLAY 0.872340 (-6125 5475);
PAINT GREEN (-6125 5475);
DISPLAY INVISIBLE (-6125 5475);
FORCEPROP 1 LAST HDL_TAP TRUE
J 0
(-5800 5300);
DISPLAY 0.872340 (-5800 5300);
DISPLAY INVISIBLE (-5800 5300);
FORCEPROP 1 LAST PATH I120
J 0
(-6127 5425);
DISPLAY 0.872340 (-6127 5425);
PAINT GREEN (-6127 5425);
DISPLAY INVISIBLE (-6127 5425);
FORCEADD TAP..1
(-6125 5475);
FORCEPROP 3 LASTPIN (-6175 5475) SIG_NAME M_F_CPU1_SA_DQ<30>
J 0
(-6165 5485);
DISPLAY 0.659574 (-6165 5485);
PAINT MONO (-6165 5485);
DISPLAY INVISIBLE (-6165 5485);
FORCEPROP 1 LASTPIN (-6175 5475) BN 30
J 0
(-6187 5483);
DISPLAY 0.489362 (-6187 5483);
PAINT GREEN (-6187 5483);
FORCEPROP 2 LAST CDS_LIB mstr_standard
J 0
(-6125 5475);
DISPLAY 0.723404 (-6125 5475);
PAINT MONO (-6125 5475);
DISPLAY INVISIBLE (-6125 5475);
FORCEPROP 1 LAST BODY_TYPE PLUMBING
J 0
(-6125 5525);
DISPLAY 0.872340 (-6125 5525);
PAINT GREEN (-6125 5525);
DISPLAY INVISIBLE (-6125 5525);
FORCEPROP 1 LAST HDL_TAP TRUE
J 0
(-5800 5350);
DISPLAY 0.872340 (-5800 5350);
DISPLAY INVISIBLE (-5800 5350);
FORCEPROP 1 LAST PATH I121
J 0
(-6127 5475);
DISPLAY 0.872340 (-6127 5475);
PAINT GREEN (-6127 5475);
DISPLAY INVISIBLE (-6127 5475);
FORCEADD TAP..1
(-6125 5375);
FORCEPROP 3 LASTPIN (-6175 5375) SIG_NAME M_F_CPU1_SA_DQ<28>
J 0
(-6165 5385);
DISPLAY 0.659574 (-6165 5385);
PAINT MONO (-6165 5385);
DISPLAY INVISIBLE (-6165 5385);
FORCEPROP 1 LASTPIN (-6175 5375) BN 28
J 0
(-6187 5383);
DISPLAY 0.489362 (-6187 5383);
PAINT GREEN (-6187 5383);
FORCEPROP 2 LAST CDS_LIB mstr_standard
J 0
(-6125 5375);
DISPLAY 0.723404 (-6125 5375);
PAINT MONO (-6125 5375);
DISPLAY INVISIBLE (-6125 5375);
FORCEPROP 1 LAST BODY_TYPE PLUMBING
J 0
(-6125 5425);
DISPLAY 0.872340 (-6125 5425);
PAINT GREEN (-6125 5425);
DISPLAY INVISIBLE (-6125 5425);
FORCEPROP 1 LAST HDL_TAP TRUE
J 0
(-5800 5250);
DISPLAY 0.872340 (-5800 5250);
DISPLAY INVISIBLE (-5800 5250);
FORCEPROP 1 LAST PATH I122
J 0
(-6127 5375);
DISPLAY 0.872340 (-6127 5375);
PAINT GREEN (-6127 5375);
DISPLAY INVISIBLE (-6127 5375);
FORCEADD TAP..1
(-6125 5325);
FORCEPROP 3 LASTPIN (-6175 5325) SIG_NAME M_F_CPU1_SA_DQ<27>
J 0
(-6165 5335);
DISPLAY 0.659574 (-6165 5335);
PAINT MONO (-6165 5335);
DISPLAY INVISIBLE (-6165 5335);
FORCEPROP 1 LASTPIN (-6175 5325) BN 27
J 0
(-6187 5333);
DISPLAY 0.489362 (-6187 5333);
PAINT GREEN (-6187 5333);
FORCEPROP 2 LAST CDS_LIB mstr_standard
J 0
(-6125 5325);
DISPLAY 0.723404 (-6125 5325);
PAINT MONO (-6125 5325);
DISPLAY INVISIBLE (-6125 5325);
FORCEPROP 1 LAST BODY_TYPE PLUMBING
J 0
(-6125 5375);
DISPLAY 0.872340 (-6125 5375);
PAINT GREEN (-6125 5375);
DISPLAY INVISIBLE (-6125 5375);
FORCEPROP 1 LAST HDL_TAP TRUE
J 0
(-5800 5200);
DISPLAY 0.872340 (-5800 5200);
DISPLAY INVISIBLE (-5800 5200);
FORCEPROP 1 LAST PATH I123
J 0
(-6127 5325);
DISPLAY 0.872340 (-6127 5325);
PAINT GREEN (-6127 5325);
DISPLAY INVISIBLE (-6127 5325);
FORCEADD TAP..1
(-6125 5275);
FORCEPROP 3 LASTPIN (-6175 5275) SIG_NAME M_F_CPU1_SA_DQ<26>
J 0
(-6165 5285);
DISPLAY 0.659574 (-6165 5285);
PAINT MONO (-6165 5285);
DISPLAY INVISIBLE (-6165 5285);
FORCEPROP 1 LASTPIN (-6175 5275) BN 26
J 0
(-6187 5283);
DISPLAY 0.489362 (-6187 5283);
PAINT GREEN (-6187 5283);
FORCEPROP 2 LAST CDS_LIB mstr_standard
J 0
(-6125 5275);
DISPLAY 0.723404 (-6125 5275);
PAINT MONO (-6125 5275);
DISPLAY INVISIBLE (-6125 5275);
FORCEPROP 1 LAST BODY_TYPE PLUMBING
J 0
(-6125 5325);
DISPLAY 0.872340 (-6125 5325);
PAINT GREEN (-6125 5325);
DISPLAY INVISIBLE (-6125 5325);
FORCEPROP 1 LAST HDL_TAP TRUE
J 0
(-5800 5150);
DISPLAY 0.872340 (-5800 5150);
DISPLAY INVISIBLE (-5800 5150);
FORCEPROP 1 LAST PATH I124
J 0
(-6127 5275);
DISPLAY 0.872340 (-6127 5275);
PAINT GREEN (-6127 5275);
DISPLAY INVISIBLE (-6127 5275);
FORCEADD TAP..1
(-6125 5525);
FORCEPROP 3 LASTPIN (-6175 5525) SIG_NAME M_F_CPU1_SA_DQ<31>
J 0
(-6165 5535);
DISPLAY 0.659574 (-6165 5535);
PAINT MONO (-6165 5535);
DISPLAY INVISIBLE (-6165 5535);
FORCEPROP 1 LASTPIN (-6175 5525) BN 31
J 0
(-6187 5533);
DISPLAY 0.489362 (-6187 5533);
PAINT GREEN (-6187 5533);
FORCEPROP 2 LAST CDS_LIB mstr_standard
J 0
(-6125 5525);
DISPLAY 0.723404 (-6125 5525);
PAINT MONO (-6125 5525);
DISPLAY INVISIBLE (-6125 5525);
FORCEPROP 1 LAST BODY_TYPE PLUMBING
J 0
(-6125 5575);
DISPLAY 0.872340 (-6125 5575);
PAINT GREEN (-6125 5575);
DISPLAY INVISIBLE (-6125 5575);
FORCEPROP 1 LAST HDL_TAP TRUE
J 0
(-5800 5400);
DISPLAY 0.872340 (-5800 5400);
DISPLAY INVISIBLE (-5800 5400);
FORCEPROP 1 LAST PATH I125
J 0
(-6127 5525);
DISPLAY 0.872340 (-6127 5525);
PAINT GREEN (-6127 5525);
DISPLAY INVISIBLE (-6127 5525);
FORCEADD OFFPAGE..3
(-5375 5575);
FORCEPROP 2 LAST $XR0 42 
J 0
(-5161 5575);
DISPLAY 0.638298 (-5161 5575);
PAINT MONO (-5161 5575);
FORCEPROP 2 LAST PATH I126
J 0
(-5150 5625);
DISPLAY 1.021277 (-5150 5625);
DISPLAY INVISIBLE (-5150 5625);
FORCEPROP 1 LAST COMMENT_BODY TRUE
J 0
(-5425 5475);
DISPLAY 0.872340 (-5425 5475);
PAINT GREEN (-5425 5475);
DISPLAY INVISIBLE (-5425 5475);
FORCEPROP 1 LAST OFFPAGE TRUE
J 0
(-5050 5450);
DISPLAY 0.872340 (-5050 5450);
PAINT GREEN (-5050 5450);
DISPLAY INVISIBLE (-5050 5450);
FORCEPROP 2 LAST CDS_LIB mstr_standard
J 0
(-5375 5575);
DISPLAY 0.723404 (-5375 5575);
PAINT MONO (-5375 5575);
DISPLAY INVISIBLE (-5375 5575);
FORCEADD OFFPAGE..5
(-7325 1450);
FORCEPROP 2 LAST $XR0 102 
J 0
(-7580 1450);
DISPLAY 0.638298 (-7580 1450);
PAINT MONO (-7580 1450);
FORCEPROP 2 LAST PATH I127
J 0
(-7575 1500);
DISPLAY 1.021277 (-7575 1500);
DISPLAY INVISIBLE (-7575 1500);
FORCEPROP 1 LAST COMMENT_BODY TRUE
J 0
(-7225 1375);
DISPLAY 0.872340 (-7225 1375);
PAINT GREEN (-7225 1375);
DISPLAY INVISIBLE (-7225 1375);
FORCEPROP 1 LAST OFFPAGE TRUE
J 0
(-7000 1325);
DISPLAY 0.872340 (-7000 1325);
PAINT GREEN (-7000 1325);
DISPLAY INVISIBLE (-7000 1325);
FORCEPROP 2 LAST BOM_COST MEM
J 0
(-7400 1525);
DISPLAY 0.808511 (-7400 1525);
DISPLAY INVISIBLE (-7400 1525);
FORCEPROP 2 LAST CDS_LIB mstr_standard
J 0
(-7325 1450);
DISPLAY 0.808511 (-7325 1450);
DISPLAY INVISIBLE (-7325 1450);
FORCEADD GND..1
(-6550 1050);
FORCEPROP 3 LASTPIN (-6550 1100) SIG_NAME GND\g
J 0
(-6540 1110);
DISPLAY 0.659574 (-6540 1110);
PAINT MONO (-6540 1110);
DISPLAY INVISIBLE (-6540 1110);
FORCEPROP 1 LAST SIZE 1B
J 0
(-6475 1000);
DISPLAY 0.851064 (-6475 1000);
PAINT GREEN (-6475 1000);
DISPLAY INVISIBLE (-6475 1000);
FORCEPROP 2 LAST CDS_LIB mstr_symbols
J 0
(-6550 1050);
DISPLAY 0.808511 (-6550 1050);
DISPLAY INVISIBLE (-6550 1050);
FORCEPROP 2 LAST BOM_COST MEM
J 0
(-6650 1125);
DISPLAY 0.808511 (-6650 1125);
DISPLAY INVISIBLE (-6650 1125);
FORCEPROP 1 LAST BODY_TYPE PLUMBING
J 0
(-6595 1007);
DISPLAY 0.340426 (-6595 1007);
PAINT GREEN (-6595 1007);
DISPLAY INVISIBLE (-6595 1007);
FORCEPROP 1 LAST PATH I128
J 0
(-6475 1050);
DISPLAY 0.872340 (-6475 1050);
PAINT AQUA (-6475 1050);
DISPLAY INVISIBLE (-6475 1050);
FORCEPROP 1 LAST VOLTAGE 0.0
J 0
(-6595 1007);
DISPLAY 0.723404 (-6595 1007);
PAINT SKYBLUE (-6595 1007);
DISPLAY INVISIBLE (-6595 1007);
FORCEPROP 1 LAST HDL_POWER GND
J 0
(-6550 1200);
DISPLAY 0.851064 (-6550 1200);
PAINT GREEN (-6550 1200);
DISPLAY INVISIBLE (-6550 1200);
FORCEADD Q_RES..2
(-6550 1275);
FORCEPROP 1 LAST LOCATION R773
J 0
(-6505 1400);
DISPLAY 0.489362 (-6505 1400);
PAINT SKYBLUE (-6505 1400);
FORCEPROP 0 LAST $SEC 1
J 0
(-6500 1450);
DISPLAY 0.680851 (-6500 1450);
PAINT MONO (-6500 1450);
DISPLAY INVISIBLE (-6500 1450);
FORCEPROP 0 LAST CDS_SEC 1
J 0
(-6500 1450);
DISPLAY 1.021277 (-6500 1450);
DISPLAY INVISIBLE (-6500 1450);
FORCEPROP 1 LASTPIN (-6550 1375) $PN 1
J 0
(-6545 1337);
DISPLAY 0.489362 (-6545 1337);
PAINT MONO (-6545 1337);
FORCEPROP 1 LASTPIN (-6550 1175) $PN 2
J 0
(-6545 1185);
DISPLAY 0.489362 (-6545 1185);
PAINT MONO (-6545 1185);
FORCEPROP 1 LAST WATTAGE 1/16W
J 0
(-6510 1250);
DISPLAY 0.489362 (-6510 1250);
PAINT SKYBLUE (-6510 1250);
FORCEPROP 1 LAST MATERIAL CHIP
J 0
(-6510 1200);
DISPLAY 0.489362 (-6510 1200);
PAINT SKYBLUE (-6510 1200);
FORCEPROP 1 LAST TOLERANCE 1%
J 0
(-6505 1300);
DISPLAY 0.489362 (-6505 1300);
PAINT SKYBLUE (-6505 1300);
FORCEPROP 1 LAST VALUE 84.5K
J 0
(-6505 1350);
DISPLAY 0.489362 (-6505 1350);
PAINT SKYBLUE (-6505 1350);
FORCEPROP 1 LAST PART_NUMBER CS38452FB05
J 0
(-6510 1150);
DISPLAY 0.489362 (-6510 1150);
PAINT SKYBLUE (-6510 1150);
FORCEPROP 1 LAST PACK_TYPE 0402LF
J 0
(-6510 1100);
DISPLAY 0.489362 (-6510 1100);
PAINT SKYBLUE (-6510 1100);
FORCEPROP 2 LAST CDS_LIB pure_quanta
J 0
(-6550 1275);
DISPLAY INVISIBLE (-6550 1275);
FORCEPROP 1 LAST PATH I129
J 0
(-6500 1450);
DISPLAY 0.978723 (-6500 1450);
PAINT WHITE (-6500 1450);
DISPLAY INVISIBLE (-6500 1450);
FORCEADD OFFPAGE..1
(-8425 4375);
FORCEPROP 2 LAST $XR0 42 
J 0
(-8646 4375);
DISPLAY 0.638298 (-8646 4375);
PAINT MONO (-8646 4375);
FORCEPROP 2 LAST PATH I13
J 0
(-8675 4425);
DISPLAY 1.021277 (-8675 4425);
DISPLAY INVISIBLE (-8675 4425);
FORCEPROP 1 LAST COMMENT_BODY TRUE
J 0
(-8300 4275);
DISPLAY 0.872340 (-8300 4275);
PAINT GREEN (-8300 4275);
DISPLAY INVISIBLE (-8300 4275);
FORCEPROP 1 LAST OFFPAGE TRUE
J 0
(-8100 4250);
DISPLAY 0.872340 (-8100 4250);
PAINT GREEN (-8100 4250);
DISPLAY INVISIBLE (-8100 4250);
FORCEPROP 2 LAST CDS_LIB mstr_standard
J 0
(-8425 4375);
DISPLAY 0.808511 (-8425 4375);
DISPLAY INVISIBLE (-8425 4375);
FORCEADD OFFPAGE..1
(-8425 4275);
FORCEPROP 2 LAST $XR0 42 
J 0
(-8646 4275);
DISPLAY 0.638298 (-8646 4275);
PAINT MONO (-8646 4275);
FORCEPROP 2 LAST PATH I14
J 0
(-8675 4325);
DISPLAY 1.021277 (-8675 4325);
DISPLAY INVISIBLE (-8675 4325);
FORCEPROP 1 LAST COMMENT_BODY TRUE
J 0
(-8300 4175);
DISPLAY 0.872340 (-8300 4175);
PAINT GREEN (-8300 4175);
DISPLAY INVISIBLE (-8300 4175);
FORCEPROP 1 LAST OFFPAGE TRUE
J 0
(-8100 4150);
DISPLAY 0.872340 (-8100 4150);
PAINT GREEN (-8100 4150);
DISPLAY INVISIBLE (-8100 4150);
FORCEPROP 2 LAST CDS_LIB mstr_standard
J 0
(-8425 4275);
DISPLAY 0.723404 (-8425 4275);
PAINT MONO (-8425 4275);
DISPLAY INVISIBLE (-8425 4275);
FORCEADD GND..1
(-2200 2000);
FORCEPROP 3 LASTPIN (-2200 2050) SIG_NAME GND\g
J 0
(-2190 2060);
DISPLAY 0.659574 (-2190 2060);
PAINT MONO (-2190 2060);
DISPLAY INVISIBLE (-2190 2060);
FORCEPROP 1 LAST SIZE 1B
J 0
(-2125 1950);
DISPLAY 0.851064 (-2125 1950);
PAINT GREEN (-2125 1950);
DISPLAY INVISIBLE (-2125 1950);
FORCEPROP 2 LAST CDS_LIB mstr_symbols
J 0
(-2200 2000);
DISPLAY 0.723404 (-2200 2000);
DISPLAY INVISIBLE (-2200 2000);
FORCEPROP 1 LAST BODY_TYPE PLUMBING
J 0
(-2245 1957);
DISPLAY 0.340426 (-2245 1957);
PAINT GREEN (-2245 1957);
DISPLAY INVISIBLE (-2245 1957);
FORCEPROP 1 LAST PATH I140
J 0
(-2125 2000);
DISPLAY 0.872340 (-2125 2000);
PAINT AQUA (-2125 2000);
DISPLAY INVISIBLE (-2125 2000);
FORCEPROP 1 LAST VOLTAGE 0.0
J 0
(-2245 1957);
DISPLAY 0.723404 (-2245 1957);
PAINT SKYBLUE (-2245 1957);
DISPLAY INVISIBLE (-2245 1957);
FORCEPROP 1 LAST HDL_POWER GND
J 0
(-2200 2150);
DISPLAY 0.851064 (-2200 2150);
PAINT GREEN (-2200 2150);
DISPLAY INVISIBLE (-2200 2150);
FORCEADD GND..1
(-400 1775);
FORCEPROP 3 LASTPIN (-400 1825) SIG_NAME GND\g
J 0
(-390 1835);
DISPLAY 0.659574 (-390 1835);
PAINT MONO (-390 1835);
DISPLAY INVISIBLE (-390 1835);
FORCEPROP 2 LAST CDS_LIB mstr_symbols
J 0
(-400 1775);
DISPLAY 0.723404 (-400 1775);
DISPLAY INVISIBLE (-400 1775);
FORCEPROP 1 LAST SIZE 1B
J 0
(-325 1725);
DISPLAY 0.851064 (-325 1725);
PAINT GREEN (-325 1725);
DISPLAY INVISIBLE (-325 1725);
FORCEPROP 1 LAST BODY_TYPE PLUMBING
J 0
(-445 1732);
DISPLAY 0.340426 (-445 1732);
PAINT GREEN (-445 1732);
DISPLAY INVISIBLE (-445 1732);
FORCEPROP 1 LAST PATH I141
J 0
(-325 1775);
DISPLAY 0.872340 (-325 1775);
PAINT AQUA (-325 1775);
DISPLAY INVISIBLE (-325 1775);
FORCEPROP 1 LAST VOLTAGE 0.0
J 0
(-445 1732);
DISPLAY 0.723404 (-445 1732);
PAINT SKYBLUE (-445 1732);
DISPLAY INVISIBLE (-445 1732);
FORCEPROP 1 LAST HDL_POWER GND
J 0
(-400 1925);
DISPLAY 0.851064 (-400 1925);
PAINT GREEN (-400 1925);
DISPLAY INVISIBLE (-400 1925);
FORCEADD SCONN288_DDR506112002KQ..3
(-1300 3775);
FORCEPROP 1 LAST LOCATION J33
J 0
(-1750 5750);
DISPLAY 0.468085 (-1750 5750);
PAINT SKYBLUE (-1750 5750);
FORCEPROP 0 LAST $SEC 3
J 0
(-1750 5900);
DISPLAY 0.680851 (-1750 5900);
PAINT MONO (-1750 5900);
DISPLAY INVISIBLE (-1750 5900);
FORCEPROP 2 LAST CDS_SEC 3
J 0
(-1750 5900);
DISPLAY 1.021277 (-1750 5900);
DISPLAY INVISIBLE (-1750 5900);
FORCEPROP 0 LASTPIN (-700 2175) $PN G1
J 0
(-690 2185);
DISPLAY 0.680851 (-690 2185);
PAINT MONO (-690 2185);
FORCEPROP 0 LASTPIN (-700 2125) $PN G2
J 0
(-690 2135);
DISPLAY 0.680851 (-690 2135);
PAINT MONO (-690 2135);
FORCEPROP 0 LASTPIN (-700 2075) $PN G3
J 0
(-690 2085);
DISPLAY 0.680851 (-690 2085);
PAINT MONO (-690 2085);
FORCEPROP 0 LASTPIN (-1900 5325) $PN 1
J 2
(-1910 5335);
DISPLAY 0.680851 (-1910 5335);
PAINT MONO (-1910 5335);
FORCEPROP 0 LASTPIN (-1900 5375) $PN 145
J 2
(-1910 5385);
DISPLAY 0.680851 (-1910 5385);
PAINT MONO (-1910 5385);
FORCEPROP 0 LASTPIN (-1900 5425) $PN 146
J 2
(-1910 5435);
DISPLAY 0.680851 (-1910 5435);
PAINT MONO (-1910 5435);
FORCEPROP 0 LASTPIN (-700 2275) $PN 6
J 0
(-690 2285);
DISPLAY 0.680851 (-690 2285);
PAINT MONO (-690 2285);
FORCEPROP 0 LASTPIN (-700 2325) $PN 8
J 0
(-690 2335);
DISPLAY 0.680851 (-690 2335);
PAINT MONO (-690 2335);
FORCEPROP 0 LASTPIN (-700 2375) $PN 10
J 0
(-690 2385);
DISPLAY 0.680851 (-690 2385);
PAINT MONO (-690 2385);
FORCEPROP 0 LASTPIN (-700 2425) $PN 13
J 0
(-690 2435);
DISPLAY 0.680851 (-690 2435);
PAINT MONO (-690 2435);
FORCEPROP 0 LASTPIN (-700 2475) $PN 15
J 0
(-690 2485);
DISPLAY 0.680851 (-690 2485);
PAINT MONO (-690 2485);
FORCEPROP 0 LASTPIN (-700 2525) $PN 17
J 0
(-690 2535);
DISPLAY 0.680851 (-690 2535);
PAINT MONO (-690 2535);
FORCEPROP 0 LASTPIN (-700 2575) $PN 19
J 0
(-690 2585);
DISPLAY 0.680851 (-690 2585);
PAINT MONO (-690 2585);
FORCEPROP 0 LASTPIN (-700 2625) $PN 21
J 0
(-690 2635);
DISPLAY 0.680851 (-690 2635);
PAINT MONO (-690 2635);
FORCEPROP 0 LASTPIN (-700 2675) $PN 24
J 0
(-690 2685);
DISPLAY 0.680851 (-690 2685);
PAINT MONO (-690 2685);
FORCEPROP 0 LASTPIN (-700 2725) $PN 26
J 0
(-690 2735);
DISPLAY 0.680851 (-690 2735);
PAINT MONO (-690 2735);
FORCEPROP 0 LASTPIN (-700 2775) $PN 28
J 0
(-690 2785);
DISPLAY 0.680851 (-690 2785);
PAINT MONO (-690 2785);
FORCEPROP 0 LASTPIN (-700 2825) $PN 30
J 0
(-690 2835);
DISPLAY 0.680851 (-690 2835);
PAINT MONO (-690 2835);
FORCEPROP 0 LASTPIN (-700 2875) $PN 32
J 0
(-690 2885);
DISPLAY 0.680851 (-690 2885);
PAINT MONO (-690 2885);
FORCEPROP 0 LASTPIN (-700 2925) $PN 35
J 0
(-690 2935);
DISPLAY 0.680851 (-690 2935);
PAINT MONO (-690 2935);
FORCEPROP 0 LASTPIN (-700 2975) $PN 37
J 0
(-690 2985);
DISPLAY 0.680851 (-690 2985);
PAINT MONO (-690 2985);
FORCEPROP 0 LASTPIN (-700 3025) $PN 39
J 0
(-690 3035);
DISPLAY 0.680851 (-690 3035);
PAINT MONO (-690 3035);
FORCEPROP 0 LASTPIN (-700 3075) $PN 41
J 0
(-690 3085);
DISPLAY 0.680851 (-690 3085);
PAINT MONO (-690 3085);
FORCEPROP 0 LASTPIN (-700 3125) $PN 43
J 0
(-690 3135);
DISPLAY 0.680851 (-690 3135);
PAINT MONO (-690 3135);
FORCEPROP 0 LASTPIN (-700 3175) $PN 46
J 0
(-690 3185);
DISPLAY 0.680851 (-690 3185);
PAINT MONO (-690 3185);
FORCEPROP 0 LASTPIN (-700 3225) $PN 48
J 0
(-690 3235);
DISPLAY 0.680851 (-690 3235);
PAINT MONO (-690 3235);
FORCEPROP 0 LASTPIN (-700 3275) $PN 50
J 0
(-690 3285);
DISPLAY 0.680851 (-690 3285);
PAINT MONO (-690 3285);
FORCEPROP 0 LASTPIN (-700 3325) $PN 52
J 0
(-690 3335);
DISPLAY 0.680851 (-690 3335);
PAINT MONO (-690 3335);
FORCEPROP 0 LASTPIN (-700 3375) $PN 54
J 0
(-690 3385);
DISPLAY 0.680851 (-690 3385);
PAINT MONO (-690 3385);
FORCEPROP 0 LASTPIN (-700 3425) $PN 57
J 0
(-690 3435);
DISPLAY 0.680851 (-690 3435);
PAINT MONO (-690 3435);
FORCEPROP 0 LASTPIN (-700 3475) $PN 59
J 0
(-690 3485);
DISPLAY 0.680851 (-690 3485);
PAINT MONO (-690 3485);
FORCEPROP 0 LASTPIN (-700 3525) $PN 61
J 0
(-690 3535);
DISPLAY 0.680851 (-690 3535);
PAINT MONO (-690 3535);
FORCEPROP 0 LASTPIN (-700 3575) $PN 63
J 0
(-690 3585);
DISPLAY 0.680851 (-690 3585);
PAINT MONO (-690 3585);
FORCEPROP 0 LASTPIN (-700 3625) $PN 65
J 0
(-690 3635);
DISPLAY 0.680851 (-690 3635);
PAINT MONO (-690 3635);
FORCEPROP 0 LASTPIN (-700 3675) $PN 67
J 0
(-690 3685);
DISPLAY 0.680851 (-690 3685);
PAINT MONO (-690 3685);
FORCEPROP 0 LASTPIN (-700 3725) $PN 69
J 0
(-690 3735);
DISPLAY 0.680851 (-690 3735);
PAINT MONO (-690 3735);
FORCEPROP 0 LASTPIN (-700 3775) $PN 71
J 0
(-690 3785);
DISPLAY 0.680851 (-690 3785);
PAINT MONO (-690 3785);
FORCEPROP 0 LASTPIN (-700 3825) $PN 73
J 0
(-690 3835);
DISPLAY 0.680851 (-690 3835);
PAINT MONO (-690 3835);
FORCEPROP 0 LASTPIN (-700 3875) $PN 75
J 0
(-690 3885);
DISPLAY 0.680851 (-690 3885);
PAINT MONO (-690 3885);
FORCEPROP 0 LASTPIN (-700 3925) $PN 77
J 0
(-690 3935);
DISPLAY 0.680851 (-690 3935);
PAINT MONO (-690 3935);
FORCEPROP 0 LASTPIN (-700 3975) $PN 79
J 0
(-690 3985);
DISPLAY 0.680851 (-690 3985);
PAINT MONO (-690 3985);
FORCEPROP 0 LASTPIN (-700 4025) $PN 81
J 0
(-690 4035);
DISPLAY 0.680851 (-690 4035);
PAINT MONO (-690 4035);
FORCEPROP 0 LASTPIN (-700 4075) $PN 83
J 0
(-690 4085);
DISPLAY 0.680851 (-690 4085);
PAINT MONO (-690 4085);
FORCEPROP 0 LASTPIN (-700 4125) $PN 85
J 0
(-690 4135);
DISPLAY 0.680851 (-690 4135);
PAINT MONO (-690 4135);
FORCEPROP 0 LASTPIN (-700 4175) $PN 88
J 0
(-690 4185);
DISPLAY 0.680851 (-690 4185);
PAINT MONO (-690 4185);
FORCEPROP 0 LASTPIN (-700 4225) $PN 90
J 0
(-690 4235);
DISPLAY 0.680851 (-690 4235);
PAINT MONO (-690 4235);
FORCEPROP 0 LASTPIN (-700 4275) $PN 92
J 0
(-690 4285);
DISPLAY 0.680851 (-690 4285);
PAINT MONO (-690 4285);
FORCEPROP 0 LASTPIN (-700 4325) $PN 95
J 0
(-690 4335);
DISPLAY 0.680851 (-690 4335);
PAINT MONO (-690 4335);
FORCEPROP 0 LASTPIN (-700 4375) $PN 97
J 0
(-690 4385);
DISPLAY 0.680851 (-690 4385);
PAINT MONO (-690 4385);
FORCEPROP 0 LASTPIN (-700 4425) $PN 99
J 0
(-690 4435);
DISPLAY 0.680851 (-690 4435);
PAINT MONO (-690 4435);
FORCEPROP 0 LASTPIN (-700 4475) $PN 101
J 0
(-690 4485);
DISPLAY 0.680851 (-690 4485);
PAINT MONO (-690 4485);
FORCEPROP 0 LASTPIN (-700 4525) $PN 103
J 0
(-690 4535);
DISPLAY 0.680851 (-690 4535);
PAINT MONO (-690 4535);
FORCEPROP 0 LASTPIN (-700 4575) $PN 106
J 0
(-690 4585);
DISPLAY 0.680851 (-690 4585);
PAINT MONO (-690 4585);
FORCEPROP 0 LASTPIN (-700 4625) $PN 108
J 0
(-690 4635);
DISPLAY 0.680851 (-690 4635);
PAINT MONO (-690 4635);
FORCEPROP 0 LASTPIN (-700 4675) $PN 110
J 0
(-690 4685);
DISPLAY 0.680851 (-690 4685);
PAINT MONO (-690 4685);
FORCEPROP 0 LASTPIN (-700 4725) $PN 112
J 0
(-690 4735);
DISPLAY 0.680851 (-690 4735);
PAINT MONO (-690 4735);
FORCEPROP 0 LASTPIN (-700 4775) $PN 114
J 0
(-690 4785);
DISPLAY 0.680851 (-690 4785);
PAINT MONO (-690 4785);
FORCEPROP 0 LASTPIN (-700 4825) $PN 117
J 0
(-690 4835);
DISPLAY 0.680851 (-690 4835);
PAINT MONO (-690 4835);
FORCEPROP 0 LASTPIN (-700 4875) $PN 119
J 0
(-690 4885);
DISPLAY 0.680851 (-690 4885);
PAINT MONO (-690 4885);
FORCEPROP 0 LASTPIN (-700 4925) $PN 121
J 0
(-690 4935);
DISPLAY 0.680851 (-690 4935);
PAINT MONO (-690 4935);
FORCEPROP 0 LASTPIN (-700 4975) $PN 123
J 0
(-690 4985);
DISPLAY 0.680851 (-690 4985);
PAINT MONO (-690 4985);
FORCEPROP 0 LASTPIN (-700 5025) $PN 125
J 0
(-690 5035);
DISPLAY 0.680851 (-690 5035);
PAINT MONO (-690 5035);
FORCEPROP 0 LASTPIN (-700 5075) $PN 128
J 0
(-690 5085);
DISPLAY 0.680851 (-690 5085);
PAINT MONO (-690 5085);
FORCEPROP 0 LASTPIN (-700 5125) $PN 130
J 0
(-690 5135);
DISPLAY 0.680851 (-690 5135);
PAINT MONO (-690 5135);
FORCEPROP 0 LASTPIN (-700 5175) $PN 132
J 0
(-690 5185);
DISPLAY 0.680851 (-690 5185);
PAINT MONO (-690 5185);
FORCEPROP 0 LASTPIN (-700 5225) $PN 134
J 0
(-690 5235);
DISPLAY 0.680851 (-690 5235);
PAINT MONO (-690 5235);
FORCEPROP 0 LASTPIN (-700 5275) $PN 136
J 0
(-690 5285);
DISPLAY 0.680851 (-690 5285);
PAINT MONO (-690 5285);
FORCEPROP 0 LASTPIN (-700 5325) $PN 139
J 0
(-690 5335);
DISPLAY 0.680851 (-690 5335);
PAINT MONO (-690 5335);
FORCEPROP 0 LASTPIN (-700 5375) $PN 141
J 0
(-690 5385);
DISPLAY 0.680851 (-690 5385);
PAINT MONO (-690 5385);
FORCEPROP 0 LASTPIN (-700 5425) $PN 143
J 0
(-690 5435);
DISPLAY 0.680851 (-690 5435);
PAINT MONO (-690 5435);
FORCEPROP 0 LASTPIN (-1900 2175) $PN 151
J 2
(-1910 2185);
DISPLAY 0.680851 (-1910 2185);
PAINT MONO (-1910 2185);
FORCEPROP 0 LASTPIN (-1900 2225) $PN 153
J 2
(-1910 2235);
DISPLAY 0.680851 (-1910 2235);
PAINT MONO (-1910 2235);
FORCEPROP 0 LASTPIN (-1900 2275) $PN 155
J 2
(-1910 2285);
DISPLAY 0.680851 (-1910 2285);
PAINT MONO (-1910 2285);
FORCEPROP 0 LASTPIN (-1900 2325) $PN 158
J 2
(-1910 2335);
DISPLAY 0.680851 (-1910 2335);
PAINT MONO (-1910 2335);
FORCEPROP 0 LASTPIN (-1900 2375) $PN 160
J 2
(-1910 2385);
DISPLAY 0.680851 (-1910 2385);
PAINT MONO (-1910 2385);
FORCEPROP 0 LASTPIN (-1900 2425) $PN 162
J 2
(-1910 2435);
DISPLAY 0.680851 (-1910 2435);
PAINT MONO (-1910 2435);
FORCEPROP 0 LASTPIN (-1900 2475) $PN 164
J 2
(-1910 2485);
DISPLAY 0.680851 (-1910 2485);
PAINT MONO (-1910 2485);
FORCEPROP 0 LASTPIN (-1900 2525) $PN 166
J 2
(-1910 2535);
DISPLAY 0.680851 (-1910 2535);
PAINT MONO (-1910 2535);
FORCEPROP 0 LASTPIN (-1900 2575) $PN 169
J 2
(-1910 2585);
DISPLAY 0.680851 (-1910 2585);
PAINT MONO (-1910 2585);
FORCEPROP 0 LASTPIN (-1900 2625) $PN 171
J 2
(-1910 2635);
DISPLAY 0.680851 (-1910 2635);
PAINT MONO (-1910 2635);
FORCEPROP 0 LASTPIN (-1900 2675) $PN 173
J 2
(-1910 2685);
DISPLAY 0.680851 (-1910 2685);
PAINT MONO (-1910 2685);
FORCEPROP 0 LASTPIN (-1900 2725) $PN 175
J 2
(-1910 2735);
DISPLAY 0.680851 (-1910 2735);
PAINT MONO (-1910 2735);
FORCEPROP 0 LASTPIN (-1900 2775) $PN 177
J 2
(-1910 2785);
DISPLAY 0.680851 (-1910 2785);
PAINT MONO (-1910 2785);
FORCEPROP 0 LASTPIN (-1900 2825) $PN 180
J 2
(-1910 2835);
DISPLAY 0.680851 (-1910 2835);
PAINT MONO (-1910 2835);
FORCEPROP 0 LASTPIN (-1900 2875) $PN 182
J 2
(-1910 2885);
DISPLAY 0.680851 (-1910 2885);
PAINT MONO (-1910 2885);
FORCEPROP 0 LASTPIN (-1900 2925) $PN 184
J 2
(-1910 2935);
DISPLAY 0.680851 (-1910 2935);
PAINT MONO (-1910 2935);
FORCEPROP 0 LASTPIN (-1900 2975) $PN 186
J 2
(-1910 2985);
DISPLAY 0.680851 (-1910 2985);
PAINT MONO (-1910 2985);
FORCEPROP 0 LASTPIN (-1900 3025) $PN 188
J 2
(-1910 3035);
DISPLAY 0.680851 (-1910 3035);
PAINT MONO (-1910 3035);
FORCEPROP 0 LASTPIN (-1900 3075) $PN 191
J 2
(-1910 3085);
DISPLAY 0.680851 (-1910 3085);
PAINT MONO (-1910 3085);
FORCEPROP 0 LASTPIN (-1900 3125) $PN 193
J 2
(-1910 3135);
DISPLAY 0.680851 (-1910 3135);
PAINT MONO (-1910 3135);
FORCEPROP 0 LASTPIN (-1900 3175) $PN 195
J 2
(-1910 3185);
DISPLAY 0.680851 (-1910 3185);
PAINT MONO (-1910 3185);
FORCEPROP 0 LASTPIN (-1900 3225) $PN 197
J 2
(-1910 3235);
DISPLAY 0.680851 (-1910 3235);
PAINT MONO (-1910 3235);
FORCEPROP 0 LASTPIN (-1900 3275) $PN 199
J 2
(-1910 3285);
DISPLAY 0.680851 (-1910 3285);
PAINT MONO (-1910 3285);
FORCEPROP 0 LASTPIN (-1900 3325) $PN 202
J 2
(-1910 3335);
DISPLAY 0.680851 (-1910 3335);
PAINT MONO (-1910 3335);
FORCEPROP 0 LASTPIN (-1900 3375) $PN 204
J 2
(-1910 3385);
DISPLAY 0.680851 (-1910 3385);
PAINT MONO (-1910 3385);
FORCEPROP 0 LASTPIN (-1900 3425) $PN 206
J 2
(-1910 3435);
DISPLAY 0.680851 (-1910 3435);
PAINT MONO (-1910 3435);
FORCEPROP 0 LASTPIN (-1900 3475) $PN 208
J 2
(-1910 3485);
DISPLAY 0.680851 (-1910 3485);
PAINT MONO (-1910 3485);
FORCEPROP 0 LASTPIN (-1900 3525) $PN 210
J 2
(-1910 3535);
DISPLAY 0.680851 (-1910 3535);
PAINT MONO (-1910 3535);
FORCEPROP 0 LASTPIN (-1900 3575) $PN 212
J 2
(-1910 3585);
DISPLAY 0.680851 (-1910 3585);
PAINT MONO (-1910 3585);
FORCEPROP 0 LASTPIN (-1900 3625) $PN 214
J 2
(-1910 3635);
DISPLAY 0.680851 (-1910 3635);
PAINT MONO (-1910 3635);
FORCEPROP 0 LASTPIN (-1900 3675) $PN 216
J 2
(-1910 3685);
DISPLAY 0.680851 (-1910 3685);
PAINT MONO (-1910 3685);
FORCEPROP 0 LASTPIN (-1900 3725) $PN 219
J 2
(-1910 3735);
DISPLAY 0.680851 (-1910 3735);
PAINT MONO (-1910 3735);
FORCEPROP 0 LASTPIN (-1900 3775) $PN 222
J 2
(-1910 3785);
DISPLAY 0.680851 (-1910 3785);
PAINT MONO (-1910 3785);
FORCEPROP 0 LASTPIN (-1900 3825) $PN 224
J 2
(-1910 3835);
DISPLAY 0.680851 (-1910 3835);
PAINT MONO (-1910 3835);
FORCEPROP 0 LASTPIN (-1900 3875) $PN 226
J 2
(-1910 3885);
DISPLAY 0.680851 (-1910 3885);
PAINT MONO (-1910 3885);
FORCEPROP 0 LASTPIN (-1900 3925) $PN 228
J 2
(-1910 3935);
DISPLAY 0.680851 (-1910 3935);
PAINT MONO (-1910 3935);
FORCEPROP 0 LASTPIN (-1900 3975) $PN 230
J 2
(-1910 3985);
DISPLAY 0.680851 (-1910 3985);
PAINT MONO (-1910 3985);
FORCEPROP 0 LASTPIN (-1900 4025) $PN 233
J 2
(-1910 4035);
DISPLAY 0.680851 (-1910 4035);
PAINT MONO (-1910 4035);
FORCEPROP 0 LASTPIN (-1900 4075) $PN 235
J 2
(-1910 4085);
DISPLAY 0.680851 (-1910 4085);
PAINT MONO (-1910 4085);
FORCEPROP 0 LASTPIN (-1900 4125) $PN 237
J 2
(-1910 4135);
DISPLAY 0.680851 (-1910 4135);
PAINT MONO (-1910 4135);
FORCEPROP 0 LASTPIN (-1900 4175) $PN 240
J 2
(-1910 4185);
DISPLAY 0.680851 (-1910 4185);
PAINT MONO (-1910 4185);
FORCEPROP 0 LASTPIN (-1900 4225) $PN 242
J 2
(-1910 4235);
DISPLAY 0.680851 (-1910 4235);
PAINT MONO (-1910 4235);
FORCEPROP 0 LASTPIN (-1900 4275) $PN 244
J 2
(-1910 4285);
DISPLAY 0.680851 (-1910 4285);
PAINT MONO (-1910 4285);
FORCEPROP 0 LASTPIN (-1900 4325) $PN 246
J 2
(-1910 4335);
DISPLAY 0.680851 (-1910 4335);
PAINT MONO (-1910 4335);
FORCEPROP 0 LASTPIN (-1900 4375) $PN 248
J 2
(-1910 4385);
DISPLAY 0.680851 (-1910 4385);
PAINT MONO (-1910 4385);
FORCEPROP 0 LASTPIN (-1900 4425) $PN 251
J 2
(-1910 4435);
DISPLAY 0.680851 (-1910 4435);
PAINT MONO (-1910 4435);
FORCEPROP 0 LASTPIN (-1900 4475) $PN 253
J 2
(-1910 4485);
DISPLAY 0.680851 (-1910 4485);
PAINT MONO (-1910 4485);
FORCEPROP 0 LASTPIN (-1900 4525) $PN 255
J 2
(-1910 4535);
DISPLAY 0.680851 (-1910 4535);
PAINT MONO (-1910 4535);
FORCEPROP 0 LASTPIN (-1900 4575) $PN 257
J 2
(-1910 4585);
DISPLAY 0.680851 (-1910 4585);
PAINT MONO (-1910 4585);
FORCEPROP 0 LASTPIN (-1900 4625) $PN 259
J 2
(-1910 4635);
DISPLAY 0.680851 (-1910 4635);
PAINT MONO (-1910 4635);
FORCEPROP 0 LASTPIN (-1900 4675) $PN 262
J 2
(-1910 4685);
DISPLAY 0.680851 (-1910 4685);
PAINT MONO (-1910 4685);
FORCEPROP 0 LASTPIN (-1900 4725) $PN 264
J 2
(-1910 4735);
DISPLAY 0.680851 (-1910 4735);
PAINT MONO (-1910 4735);
FORCEPROP 0 LASTPIN (-1900 4775) $PN 266
J 2
(-1910 4785);
DISPLAY 0.680851 (-1910 4785);
PAINT MONO (-1910 4785);
FORCEPROP 0 LASTPIN (-1900 4825) $PN 268
J 2
(-1910 4835);
DISPLAY 0.680851 (-1910 4835);
PAINT MONO (-1910 4835);
FORCEPROP 0 LASTPIN (-1900 4875) $PN 270
J 2
(-1910 4885);
DISPLAY 0.680851 (-1910 4885);
PAINT MONO (-1910 4885);
FORCEPROP 0 LASTPIN (-1900 4925) $PN 273
J 2
(-1910 4935);
DISPLAY 0.680851 (-1910 4935);
PAINT MONO (-1910 4935);
FORCEPROP 0 LASTPIN (-1900 4975) $PN 275
J 2
(-1910 4985);
DISPLAY 0.680851 (-1910 4985);
PAINT MONO (-1910 4985);
FORCEPROP 0 LASTPIN (-1900 5025) $PN 277
J 2
(-1910 5035);
DISPLAY 0.680851 (-1910 5035);
PAINT MONO (-1910 5035);
FORCEPROP 0 LASTPIN (-1900 5075) $PN 279
J 2
(-1910 5085);
DISPLAY 0.680851 (-1910 5085);
PAINT MONO (-1910 5085);
FORCEPROP 0 LASTPIN (-1900 5125) $PN 281
J 2
(-1910 5135);
DISPLAY 0.680851 (-1910 5135);
PAINT MONO (-1910 5135);
FORCEPROP 0 LASTPIN (-1900 5175) $PN 284
J 2
(-1910 5185);
DISPLAY 0.680851 (-1910 5185);
PAINT MONO (-1910 5185);
FORCEPROP 0 LASTPIN (-1900 5225) $PN 286
J 2
(-1910 5235);
DISPLAY 0.680851 (-1910 5235);
PAINT MONO (-1910 5235);
FORCEPROP 0 LASTPIN (-1900 5275) $PN 288
J 2
(-1910 5285);
DISPLAY 0.680851 (-1910 5285);
PAINT MONO (-1910 5285);
FORCEPROP 2 LAST PART_TYPE SMLF
J 0
(-1750 5850);
DISPLAY 1.021277 (-1750 5850);
FORCEPROP 2 LAST VALUE SCONN288_DDR506112002KQ
J 0
(-1750 5800);
DISPLAY 0.489362 (-1750 5800);
PAINT SKYBLUE (-1750 5800);
FORCEPROP 1 LAST MATERIAL IO
J 0
(-1750 5600);
DISPLAY 0.468085 (-1750 5600);
PAINT SKYBLUE (-1750 5600);
FORCEPROP 1 LAST PART_NUMBER DFHST8FS479
J 0
(-1750 5675);
DISPLAY 0.468085 (-1750 5675);
PAINT SKYBLUE (-1750 5675);
FORCEPROP 1 LAST CDS_LMAN_SYM_OUTLINE -450,1800,450,-1750
J 0
(-1300 3775);
DISPLAY 0.468085 (-1300 3775);
PAINT GREEN (-1300 3775);
DISPLAY INVISIBLE (-1300 3775);
FORCEPROP 1 LAST PATH I142
J 0
(-1300 3775);
DISPLAY 0.723404 (-1300 3775);
PAINT GREEN (-1300 3775);
DISPLAY INVISIBLE (-1300 3775);
FORCEPROP 1 LAST NEEDS_NO_SIZE TRUE
J 0
(-1300 3775);
DISPLAY 0.723404 (-1300 3775);
PAINT GREEN (-1300 3775);
DISPLAY INVISIBLE (-1300 3775);
FORCEPROP 2 LAST CDS_LIB pure_quanta
J 0
(-1300 3775);
DISPLAY INVISIBLE (-1300 3775);
FORCEADD OFFPAGE..1
(-8425 4425);
FORCEPROP 2 LAST $XR0 42 
J 0
(-8646 4425);
DISPLAY 0.638298 (-8646 4425);
PAINT MONO (-8646 4425);
FORCEPROP 2 LAST PATH I15
J 0
(-8675 4475);
DISPLAY 1.021277 (-8675 4475);
DISPLAY INVISIBLE (-8675 4475);
FORCEPROP 1 LAST COMMENT_BODY TRUE
J 0
(-8300 4325);
DISPLAY 0.872340 (-8300 4325);
PAINT GREEN (-8300 4325);
DISPLAY INVISIBLE (-8300 4325);
FORCEPROP 1 LAST OFFPAGE TRUE
J 0
(-8100 4300);
DISPLAY 0.872340 (-8100 4300);
PAINT GREEN (-8100 4300);
DISPLAY INVISIBLE (-8100 4300);
FORCEPROP 2 LAST CDS_LIB mstr_standard
J 0
(-8425 4425);
DISPLAY 0.723404 (-8425 4425);
PAINT MONO (-8425 4425);
DISPLAY INVISIBLE (-8425 4425);
FORCEADD OFFPAGE..1
(-8425 4675);
FORCEPROP 2 LAST $XR0 42 
J 0
(-8646 4675);
DISPLAY 0.638298 (-8646 4675);
PAINT MONO (-8646 4675);
FORCEPROP 2 LAST PATH I16
J 0
(-8675 4725);
DISPLAY 1.021277 (-8675 4725);
DISPLAY INVISIBLE (-8675 4725);
FORCEPROP 1 LAST COMMENT_BODY TRUE
J 0
(-8300 4575);
DISPLAY 0.872340 (-8300 4575);
PAINT GREEN (-8300 4575);
DISPLAY INVISIBLE (-8300 4575);
FORCEPROP 1 LAST OFFPAGE TRUE
J 0
(-8100 4550);
DISPLAY 0.872340 (-8100 4550);
PAINT GREEN (-8100 4550);
DISPLAY INVISIBLE (-8100 4550);
FORCEPROP 2 LAST CDS_LIB mstr_standard
J 0
(-8425 4675);
DISPLAY 0.808511 (-8425 4675);
DISPLAY INVISIBLE (-8425 4675);
FORCEADD OFFPAGE..1
(-8425 4525);
FORCEPROP 2 LAST $XR0 42 
J 0
(-8646 4525);
DISPLAY 0.638298 (-8646 4525);
PAINT MONO (-8646 4525);
FORCEPROP 2 LAST PATH I17
J 0
(-8675 4575);
DISPLAY 1.021277 (-8675 4575);
DISPLAY INVISIBLE (-8675 4575);
FORCEPROP 1 LAST COMMENT_BODY TRUE
J 0
(-8300 4425);
DISPLAY 0.872340 (-8300 4425);
PAINT GREEN (-8300 4425);
DISPLAY INVISIBLE (-8300 4425);
FORCEPROP 1 LAST OFFPAGE TRUE
J 0
(-8100 4400);
DISPLAY 0.872340 (-8100 4400);
PAINT GREEN (-8100 4400);
DISPLAY INVISIBLE (-8100 4400);
FORCEPROP 2 LAST CDS_LIB mstr_standard
J 0
(-8425 4525);
DISPLAY 0.808511 (-8425 4525);
DISPLAY INVISIBLE (-8425 4525);
FORCEADD OFFPAGE..6
(-8425 2975);
FORCEPROP 2 LAST $XR5 136 
J 0
(-9214 2975);
DISPLAY 0.638298 (-9214 2975);
PAINT MONO (-9214 2975);
FORCEPROP 2 LAST $XR4 101 
J 0
(-9094 2975);
DISPLAY 0.638298 (-9094 2975);
PAINT MONO (-9094 2975);
FORCEPROP 2 LAST $XR3 100 
J 0
(-8974 2975);
DISPLAY 0.638298 (-8974 2975);
PAINT MONO (-8974 2975);
FORCEPROP 2 LAST $XR2 99 
J 0
(-8854 2975);
DISPLAY 0.638298 (-8854 2975);
PAINT MONO (-8854 2975);
FORCEPROP 2 LAST $XR1 98 
J 0
(-8764 2975);
DISPLAY 0.638298 (-8764 2975);
PAINT MONO (-8764 2975);
FORCEPROP 2 LAST $XR0 97 
J 0
(-8674 2975);
DISPLAY 0.638298 (-8674 2975);
PAINT MONO (-8674 2975);
FORCEPROP 2 LAST PATH I179
J 0
(-8700 3025);
DISPLAY 1.021277 (-8700 3025);
DISPLAY INVISIBLE (-8700 3025);
FORCEPROP 1 LAST COMMENT_BODY TRUE
J 0
(-8325 2900);
DISPLAY 0.872340 (-8325 2900);
PAINT GREEN (-8325 2900);
DISPLAY INVISIBLE (-8325 2900);
FORCEPROP 1 LAST OFFPAGE TRUE
J 0
(-8100 2850);
DISPLAY 0.872340 (-8100 2850);
PAINT GREEN (-8100 2850);
DISPLAY INVISIBLE (-8100 2850);
FORCEPROP 2 LAST CDS_LIB mstr_standard
J 0
(-8425 2975);
DISPLAY 0.808511 (-8425 2975);
DISPLAY INVISIBLE (-8425 2975);
FORCEADD OFFPAGE..1
(-8425 4575);
FORCEPROP 2 LAST $XR0 42 
J 0
(-8646 4575);
DISPLAY 0.638298 (-8646 4575);
PAINT MONO (-8646 4575);
FORCEPROP 2 LAST PATH I18
J 0
(-8675 4625);
DISPLAY 1.021277 (-8675 4625);
DISPLAY INVISIBLE (-8675 4625);
FORCEPROP 1 LAST COMMENT_BODY TRUE
J 0
(-8300 4475);
DISPLAY 0.872340 (-8300 4475);
PAINT GREEN (-8300 4475);
DISPLAY INVISIBLE (-8300 4475);
FORCEPROP 1 LAST OFFPAGE TRUE
J 0
(-8100 4450);
DISPLAY 0.872340 (-8100 4450);
PAINT GREEN (-8100 4450);
DISPLAY INVISIBLE (-8100 4450);
FORCEPROP 2 LAST CDS_LIB mstr_standard
J 0
(-8425 4575);
DISPLAY 0.723404 (-8425 4575);
PAINT MONO (-8425 4575);
DISPLAY INVISIBLE (-8425 4575);
FORCEADD Q_CAP..1
R 2
(-8675 3350);
FORCEPROP 1 LAST LOCATION C156
J 2
(-8725 3450);
DISPLAY 0.489362 (-8725 3450);
PAINT SKYBLUE (-8725 3450);
FORCEPROP 0 LAST $SEC 1
J 0
(-8725 3500);
DISPLAY 0.680851 (-8725 3500);
PAINT MONO (-8725 3500);
DISPLAY INVISIBLE (-8725 3500);
FORCEPROP 0 LAST CDS_SEC 1
J 0
(-8725 3500);
DISPLAY 1.021277 (-8725 3500);
DISPLAY INVISIBLE (-8725 3500);
FORCEPROP 1 LASTPIN (-8675 3450) $PN 1
J 2
(-8685 3430);
DISPLAY 0.489362 (-8685 3430);
PAINT MONO (-8685 3430);
FORCEPROP 1 LASTPIN (-8675 3250) $PN 2
J 2
(-8685 3230);
DISPLAY 0.489362 (-8685 3230);
PAINT MONO (-8685 3230);
FORCEPROP 1 LAST TOLERANCE 10%
J 2
(-8725 3300);
DISPLAY 0.489362 (-8725 3300);
PAINT SKYBLUE (-8725 3300);
FORCEPROP 1 LAST VALUE 0.1UF
J 2
(-8725 3400);
DISPLAY 0.489362 (-8725 3400);
PAINT SKYBLUE (-8725 3400);
FORCEPROP 1 LAST VOLTAGE 25V
J 2
(-8725 3350);
DISPLAY 0.489362 (-8725 3350);
PAINT SKYBLUE (-8725 3350);
FORCEPROP 1 LAST MATERIAL X7R
J 2
(-8725 3250);
DISPLAY 0.489362 (-8725 3250);
PAINT SKYBLUE (-8725 3250);
FORCEPROP 1 LAST PACK_TYPE 0402
J 2
(-8725 3150);
DISPLAY 0.489362 (-8725 3150);
PAINT SKYBLUE (-8725 3150);
FORCEPROP 1 LAST PART_NUMBER CH4104K1B00
J 2
(-8725 3200);
DISPLAY 0.489362 (-8725 3200);
PAINT SKYBLUE (-8725 3200);
FORCEPROP 0 LAST BOM_COST MEM
J 2
(-8730 3495);
DISPLAY 0.595745 (-8730 3495);
PAINT MONO (-8730 3495);
DISPLAY INVISIBLE (-8730 3495);
FORCEPROP 2 LAST CDS_LIB pure_quanta
J 0
(-8675 3350);
DISPLAY INVISIBLE (-8675 3350);
FORCEPROP 1 LAST PATH I185
J 2
(-8725 3500);
DISPLAY 0.978723 (-8725 3500);
PAINT WHITE (-8725 3500);
DISPLAY INVISIBLE (-8725 3500);
FORCEPROP 0 LAST ROOM MEM_CH_A_CPU0_DIMM1
J 2
(-8730 3495);
DISPLAY 0.595745 (-8730 3495);
PAINT RED (-8730 3495);
DISPLAY INVISIBLE (-8730 3495);
FORCEADD GND..1
(-8675 3125);
FORCEPROP 3 LASTPIN (-8675 3175) SIG_NAME GND\g
J 0
(-8665 3185);
DISPLAY 0.659574 (-8665 3185);
PAINT MONO (-8665 3185);
DISPLAY INVISIBLE (-8665 3185);
FORCEPROP 2 LAST BOM_COST MEM
J 0
(-8650 3250);
DISPLAY 0.659574 (-8650 3250);
DISPLAY INVISIBLE (-8650 3250);
FORCEPROP 1 LAST SIZE 1B
J 0
(-8600 3075);
DISPLAY 0.723404 (-8600 3075);
PAINT GREEN (-8600 3075);
DISPLAY INVISIBLE (-8600 3075);
FORCEPROP 2 LAST CDS_LIB mstr_symbols
J 0
(-8675 3125);
DISPLAY 0.808511 (-8675 3125);
DISPLAY INVISIBLE (-8675 3125);
FORCEPROP 1 LAST BODY_TYPE PLUMBING
J 0
(-8720 3082);
DISPLAY 0.276596 (-8720 3082);
PAINT GREEN (-8720 3082);
DISPLAY INVISIBLE (-8720 3082);
FORCEPROP 1 LAST PATH I186
J 0
(-8600 3125);
DISPLAY 0.872340 (-8600 3125);
PAINT AQUA (-8600 3125);
DISPLAY INVISIBLE (-8600 3125);
FORCEPROP 1 LAST VOLTAGE 0
J 0
(-8695 3220);
DISPLAY 0.829787 (-8695 3220);
PAINT SKYBLUE (-8695 3220);
DISPLAY INVISIBLE (-8695 3220);
FORCEPROP 2 LAST ROOM MEM_EFGH_DECOUPLING_CAPS
J 0
(-8650 3200);
DISPLAY 0.659574 (-8650 3200);
PAINT RED (-8650 3200);
DISPLAY INVISIBLE (-8650 3200);
FORCEPROP 1 LAST HDL_POWER GND
J 0
(-8675 3275);
DISPLAY 0.723404 (-8675 3275);
PAINT GREEN (-8675 3275);
DISPLAY INVISIBLE (-8675 3275);
FORCEADD OFFPAGE..6
(-9100 2275);
FORCEPROP 2 LAST $XR5 81 
J 0
(-9529 2311);
DISPLAY 0.638298 (-9529 2311);
PAINT MONO (-9529 2311);
FORCEPROP 2 LAST $XR4 101 
J 0
(-9439 2311);
DISPLAY 0.638298 (-9439 2311);
PAINT MONO (-9439 2311);
FORCEPROP 2 LAST $XR3 100 
J 0
(-9439 2239);
DISPLAY 0.638298 (-9439 2239);
PAINT MONO (-9439 2239);
FORCEPROP 2 LAST $XR2 99 
J 0
(-9529 2275);
DISPLAY 0.638298 (-9529 2275);
PAINT MONO (-9529 2275);
FORCEPROP 2 LAST $XR1 98 
J 0
(-9439 2275);
DISPLAY 0.638298 (-9439 2275);
PAINT MONO (-9439 2275);
FORCEPROP 2 LAST $XR0 97 
J 0
(-9349 2275);
DISPLAY 0.638298 (-9349 2275);
PAINT MONO (-9349 2275);
FORCEPROP 2 LAST PATH I187
J 0
(-9050 2350);
DISPLAY 1.021277 (-9050 2350);
DISPLAY INVISIBLE (-9050 2350);
FORCEPROP 1 LAST COMMENT_BODY TRUE
J 0
(-9000 2200);
DISPLAY 0.872340 (-9000 2200);
PAINT GREEN (-9000 2200);
DISPLAY INVISIBLE (-9000 2200);
FORCEPROP 1 LAST OFFPAGE TRUE
J 0
(-8775 2150);
DISPLAY 0.872340 (-8775 2150);
PAINT GREEN (-8775 2150);
DISPLAY INVISIBLE (-8775 2150);
FORCEPROP 2 LAST CDS_LIB mstr_standard
J 0
(-9100 2275);
DISPLAY 0.808511 (-9100 2275);
DISPLAY INVISIBLE (-9100 2275);
FORCEADD Q_RES..1
R 2
(-8600 2275);
FORCEPROP 1 LAST LOCATION R1183
J 2
(-8575 2300);
DISPLAY 0.489362 (-8575 2300);
PAINT SKYBLUE (-8575 2300);
FORCEPROP 0 LAST $SEC 1
J 0
(-8575 2350);
DISPLAY 0.680851 (-8575 2350);
PAINT MONO (-8575 2350);
DISPLAY INVISIBLE (-8575 2350);
FORCEPROP 0 LAST CDS_SEC 1
J 0
(-8575 2350);
DISPLAY 1.021277 (-8575 2350);
DISPLAY INVISIBLE (-8575 2350);
FORCEPROP 1 LASTPIN (-8500 2275) $PN 1
J 2
(-8512 2287);
DISPLAY 0.489362 (-8512 2287);
PAINT MONO (-8512 2287);
FORCEPROP 1 LASTPIN (-8700 2275) $PN 2
J 2
(-8662 2287);
DISPLAY 0.489362 (-8662 2287);
PAINT MONO (-8662 2287);
FORCEPROP 1 LAST VALUE 0
J 0
(-8600 2225);
DISPLAY 0.489362 (-8600 2225);
PAINT SKYBLUE (-8600 2225);
FORCEPROP 2 LAST BOM_COST MEM
J 0
(-8625 2425);
DISPLAY 0.744681 (-8625 2425);
PAINT WHITE (-8625 2425);
DISPLAY INVISIBLE (-8625 2425);
FORCEPROP 2 LAST CDS_LIB pure_quanta
J 0
(-8600 2275);
DISPLAY INVISIBLE (-8600 2275);
FORCEPROP 1 LAST PATH I188
J 2
(-8550 2425);
DISPLAY 0.978723 (-8550 2425);
PAINT WHITE (-8550 2425);
DISPLAY INVISIBLE (-8550 2425);
FORCEPROP 1 LAST WATTAGE 1/16W
J 0
(-8525 2200);
DISPLAY 0.489362 (-8525 2200);
PAINT SKYBLUE (-8525 2200);
DISPLAY INVISIBLE (-8525 2200);
FORCEPROP 1 LAST MATERIAL CHIP
J 0
(-8775 2250);
DISPLAY 0.489362 (-8775 2250);
PAINT SKYBLUE (-8775 2250);
DISPLAY INVISIBLE (-8775 2250);
FORCEPROP 1 LAST TOLERANCE 5%
J 2
(-8475 2250);
DISPLAY 0.489362 (-8475 2250);
PAINT SKYBLUE (-8475 2250);
DISPLAY INVISIBLE (-8475 2250);
FORCEPROP 1 LAST PART_NUMBER CS00002JB38
J 0
(-8700 2325);
DISPLAY 0.489362 (-8700 2325);
PAINT SKYBLUE (-8700 2325);
DISPLAY INVISIBLE (-8700 2325);
FORCEPROP 1 LAST PACK_TYPE 0402LF
J 0
(-8775 2200);
DISPLAY 0.489362 (-8775 2200);
PAINT SKYBLUE (-8775 2200);
DISPLAY INVISIBLE (-8775 2200);
FORCEPROP 2 LAST ROOM RST_CPU0_PLD_TO_DIMM
J 0
(-8625 2375);
DISPLAY 0.744681 (-8625 2375);
PAINT RED (-8625 2375);
DISPLAY INVISIBLE (-8625 2375);
FORCEADD VCC_CORE..1
(-8475 2600);
FORCEPROP 3 LASTPIN (-8475 2550) SIG_NAME P3V3_STBY\g
J 0
(-8465 2560);
DISPLAY 0.659574 (-8465 2560);
PAINT MONO (-8465 2560);
DISPLAY INVISIBLE (-8465 2560);
FORCEPROP 1 LAST HDL_POWER P3V3_STBY
J 1
(-8475 2650);
DISPLAY 0.489362 (-8475 2650);
PAINT GREEN (-8475 2650);
FORCEPROP 2 LAST CDS_LIB mstr_symbols
J 0
(-8475 2600);
DISPLAY INVISIBLE (-8475 2600);
FORCEPROP 1 LAST PATH I189
J 0
(-8425 2625);
DISPLAY 0.872340 (-8425 2625);
PAINT AQUA (-8425 2625);
DISPLAY INVISIBLE (-8425 2625);
FORCEPROP 0 LAST VOLTAGE 3.3
J 0
(-8750 2750);
DISPLAY 1.021277 (-8750 2750);
PAINT SKYBLUE (-8750 2750);
DISPLAY INVISIBLE (-8750 2750);
FORCEPROP 2 LAST ROOM PVCCINFAON_CPU0_CTRL
J 0
(-8475 2700);
DISPLAY 0.808511 (-8475 2700);
PAINT RED (-8475 2700);
DISPLAY INVISIBLE (-8475 2700);
FORCEADD OFFPAGE..1
(-8425 4725);
FORCEPROP 2 LAST $XR0 42 
J 0
(-8646 4725);
DISPLAY 0.638298 (-8646 4725);
PAINT MONO (-8646 4725);
FORCEPROP 2 LAST PATH I19
J 0
(-8675 4775);
DISPLAY 1.021277 (-8675 4775);
DISPLAY INVISIBLE (-8675 4775);
FORCEPROP 1 LAST COMMENT_BODY TRUE
J 0
(-8300 4625);
DISPLAY 0.872340 (-8300 4625);
PAINT GREEN (-8300 4625);
DISPLAY INVISIBLE (-8300 4625);
FORCEPROP 1 LAST OFFPAGE TRUE
J 0
(-8100 4600);
DISPLAY 0.872340 (-8100 4600);
PAINT GREEN (-8100 4600);
DISPLAY INVISIBLE (-8100 4600);
FORCEPROP 2 LAST CDS_LIB mstr_standard
J 0
(-8425 4725);
DISPLAY 0.723404 (-8425 4725);
PAINT MONO (-8425 4725);
DISPLAY INVISIBLE (-8425 4725);
FORCEADD Q_RES..2
(-8475 2425);
FORCEPROP 1 LAST LOCATION R108
J 0
(-8430 2550);
DISPLAY 0.489362 (-8430 2550);
PAINT SKYBLUE (-8430 2550);
FORCEPROP 0 LAST $SEC 1
J 0
(-8425 2600);
DISPLAY 0.680851 (-8425 2600);
PAINT MONO (-8425 2600);
DISPLAY INVISIBLE (-8425 2600);
FORCEPROP 0 LAST CDS_SEC 1
J 0
(-8425 2600);
DISPLAY 1.021277 (-8425 2600);
DISPLAY INVISIBLE (-8425 2600);
FORCEPROP 1 LASTPIN (-8475 2525) $PN 1
J 0
(-8470 2487);
DISPLAY 0.489362 (-8470 2487);
PAINT MONO (-8470 2487);
FORCEPROP 1 LASTPIN (-8475 2325) $PN 2
J 0
(-8470 2335);
DISPLAY 0.489362 (-8470 2335);
PAINT MONO (-8470 2335);
FORCEPROP 1 LAST WATTAGE 1/16W
J 0
(-8425 2450);
DISPLAY 0.489362 (-8425 2450);
PAINT SKYBLUE (-8425 2450);
FORCEPROP 1 LAST MATERIAL EMPTY
J 0
(-8425 2425);
DISPLAY 0.489362 (-8425 2425);
PAINT RED (-8425 2425);
FORCEPROP 1 LAST TOLERANCE 5%
J 0
(-8425 2475);
DISPLAY 0.489362 (-8425 2475);
PAINT SKYBLUE (-8425 2475);
FORCEPROP 1 LAST VALUE 1K
J 0
(-8430 2500);
DISPLAY 0.489362 (-8430 2500);
PAINT SKYBLUE (-8430 2500);
FORCEPROP 1 LAST PACK_TYPE 0402LF
J 0
(-8425 2375);
DISPLAY 0.489362 (-8425 2375);
PAINT SKYBLUE (-8425 2375);
FORCEPROP 2 LAST CDS_LIB pure_quanta
J 2
(-8475 2425);
DISPLAY INVISIBLE (-8475 2425);
FORCEPROP 2 LAST BOM_COST MEM
J 0
(-8425 2600);
DISPLAY 0.808511 (-8425 2600);
DISPLAY INVISIBLE (-8425 2600);
FORCEPROP 1 LAST PATH I190
J 0
(-8425 2600);
DISPLAY 0.978723 (-8425 2600);
PAINT WHITE (-8425 2600);
DISPLAY INVISIBLE (-8425 2600);
FORCEPROP 1 LAST PART_NUMBER TMP_QCS21002JB34
J 0
(-8425 2400);
DISPLAY 0.489362 (-8425 2400);
PAINT SKYBLUE (-8425 2400);
DISPLAY INVISIBLE (-8425 2400);
FORCEPROP 2 LAST ROOM MEM_CH_A_CPU0_DIMM1
J 0
(-8425 2650);
DISPLAY 0.808511 (-8425 2650);
PAINT RED (-8425 2650);
DISPLAY INVISIBLE (-8425 2650);
FORCEADD TAP..1
(-3500 4000);
FORCEPROP 3 LASTPIN (-3550 4000) SIG_NAME M_F_CPU1_SA_DQS_DP<2>
J 0
(-3540 4010);
DISPLAY 0.659574 (-3540 4010);
PAINT MONO (-3540 4010);
DISPLAY INVISIBLE (-3540 4010);
FORCEPROP 1 LASTPIN (-3550 4000) BN 2
J 0
(-3562 4008);
DISPLAY 0.489362 (-3562 4008);
PAINT GREEN (-3562 4008);
FORCEPROP 2 LAST CDS_LIB mstr_standard
J 0
(-3500 4000);
DISPLAY 0.723404 (-3500 4000);
PAINT MONO (-3500 4000);
DISPLAY INVISIBLE (-3500 4000);
FORCEPROP 1 LAST BODY_TYPE PLUMBING
J 0
(-3500 4050);
DISPLAY 0.872340 (-3500 4050);
PAINT GREEN (-3500 4050);
DISPLAY INVISIBLE (-3500 4050);
FORCEPROP 1 LAST HDL_TAP TRUE
J 0
(-3175 3875);
DISPLAY 0.872340 (-3175 3875);
DISPLAY INVISIBLE (-3175 3875);
FORCEPROP 1 LAST PATH I191
J 0
(-3502 4000);
DISPLAY 0.872340 (-3502 4000);
PAINT GREEN (-3502 4000);
DISPLAY INVISIBLE (-3502 4000);
FORCEADD TAP..1
(-3500 4200);
FORCEPROP 3 LASTPIN (-3550 4200) SIG_NAME M_F_CPU1_SA_DQS_DP<4>
J 0
(-3540 4210);
DISPLAY 0.659574 (-3540 4210);
PAINT MONO (-3540 4210);
DISPLAY INVISIBLE (-3540 4210);
FORCEPROP 1 LASTPIN (-3550 4200) BN 4
J 0
(-3562 4208);
DISPLAY 0.489362 (-3562 4208);
PAINT GREEN (-3562 4208);
FORCEPROP 2 LAST CDS_LIB mstr_standard
J 0
(-3500 4200);
DISPLAY 0.723404 (-3500 4200);
PAINT MONO (-3500 4200);
DISPLAY INVISIBLE (-3500 4200);
FORCEPROP 1 LAST BODY_TYPE PLUMBING
J 0
(-3500 4250);
DISPLAY 0.872340 (-3500 4250);
PAINT GREEN (-3500 4250);
DISPLAY INVISIBLE (-3500 4250);
FORCEPROP 1 LAST HDL_TAP TRUE
J 0
(-3175 4075);
DISPLAY 0.872340 (-3175 4075);
DISPLAY INVISIBLE (-3175 4075);
FORCEPROP 1 LAST PATH I193
J 0
(-3502 4200);
DISPLAY 0.872340 (-3502 4200);
PAINT GREEN (-3502 4200);
DISPLAY INVISIBLE (-3502 4200);
FORCEADD OFFPAGE..2
(-2500 4700);
FORCEPROP 2 LAST $XR0 42 
J 0
(-2311 4700);
DISPLAY 0.638298 (-2311 4700);
PAINT MONO (-2311 4700);
FORCEPROP 1 LAST COMMENT_BODY TRUE
J 0
(-2545 4605);
DISPLAY 0.872340 (-2545 4605);
PAINT GREEN (-2545 4605);
DISPLAY INVISIBLE (-2545 4605);
FORCEPROP 1 LAST OFFPAGE TRUE
J 0
(-2175 4575);
DISPLAY 0.723404 (-2175 4575);
PAINT GREEN (-2175 4575);
DISPLAY INVISIBLE (-2175 4575);
FORCEPROP 2 LAST CDS_LIB mstr_standard
J 0
(-2500 4700);
DISPLAY 0.723404 (-2500 4700);
PAINT MONO (-2500 4700);
DISPLAY INVISIBLE (-2500 4700);
FORCEPROP 2 LAST PATH I194
J 0
(-2300 4750);
DISPLAY 0.680851 (-2300 4750);
DISPLAY INVISIBLE (-2300 4750);
FORCEADD OFFPAGE..2
(-2500 4750);
FORCEPROP 2 LAST $XR0 42 
J 0
(-2311 4750);
DISPLAY 0.638298 (-2311 4750);
PAINT MONO (-2311 4750);
FORCEPROP 1 LAST COMMENT_BODY TRUE
J 0
(-2545 4655);
DISPLAY 0.872340 (-2545 4655);
PAINT GREEN (-2545 4655);
DISPLAY INVISIBLE (-2545 4655);
FORCEPROP 1 LAST OFFPAGE TRUE
J 0
(-2175 4625);
DISPLAY 0.723404 (-2175 4625);
PAINT GREEN (-2175 4625);
DISPLAY INVISIBLE (-2175 4625);
FORCEPROP 2 LAST CDS_LIB mstr_standard
J 0
(-2500 4750);
DISPLAY 0.723404 (-2500 4750);
PAINT MONO (-2500 4750);
DISPLAY INVISIBLE (-2500 4750);
FORCEPROP 2 LAST PATH I195
J 0
(-2300 4800);
DISPLAY 0.680851 (-2300 4800);
DISPLAY INVISIBLE (-2300 4800);
FORCEADD OFFPAGE..2
(-2500 3650);
FORCEPROP 2 LAST $XR0 42 
J 0
(-2311 3650);
DISPLAY 0.638298 (-2311 3650);
PAINT MONO (-2311 3650);
FORCEPROP 1 LAST COMMENT_BODY TRUE
J 0
(-2545 3555);
DISPLAY 0.872340 (-2545 3555);
PAINT GREEN (-2545 3555);
DISPLAY INVISIBLE (-2545 3555);
FORCEPROP 1 LAST OFFPAGE TRUE
J 0
(-2175 3525);
DISPLAY 0.723404 (-2175 3525);
PAINT GREEN (-2175 3525);
DISPLAY INVISIBLE (-2175 3525);
FORCEPROP 2 LAST CDS_LIB mstr_standard
J 0
(-2500 3650);
DISPLAY 0.723404 (-2500 3650);
PAINT MONO (-2500 3650);
DISPLAY INVISIBLE (-2500 3650);
FORCEPROP 2 LAST PATH I196
J 0
(-2300 3700);
DISPLAY 0.680851 (-2300 3700);
DISPLAY INVISIBLE (-2300 3700);
FORCEADD OFFPAGE..2
(-2500 3700);
FORCEPROP 2 LAST $XR0 42 
J 0
(-2311 3700);
DISPLAY 0.638298 (-2311 3700);
PAINT MONO (-2311 3700);
FORCEPROP 1 LAST COMMENT_BODY TRUE
J 0
(-2545 3605);
DISPLAY 0.872340 (-2545 3605);
PAINT GREEN (-2545 3605);
DISPLAY INVISIBLE (-2545 3605);
FORCEPROP 1 LAST OFFPAGE TRUE
J 0
(-2175 3575);
DISPLAY 0.723404 (-2175 3575);
PAINT GREEN (-2175 3575);
DISPLAY INVISIBLE (-2175 3575);
FORCEPROP 2 LAST CDS_LIB mstr_standard
J 0
(-2500 3700);
DISPLAY 0.723404 (-2500 3700);
PAINT MONO (-2500 3700);
DISPLAY INVISIBLE (-2500 3700);
FORCEPROP 2 LAST PATH I197
J 0
(-2300 3750);
DISPLAY 0.680851 (-2300 3750);
DISPLAY INVISIBLE (-2300 3750);
FORCEADD TAP..1
(-3300 4650);
FORCEPROP 3 LASTPIN (-3350 4650) SIG_NAME M_F_CPU1_SA_DQS_DN<9>
J 0
(-3340 4660);
DISPLAY 0.659574 (-3340 4660);
PAINT MONO (-3340 4660);
DISPLAY INVISIBLE (-3340 4660);
FORCEPROP 1 LASTPIN (-3350 4650) BN 9
J 0
(-3362 4658);
DISPLAY 0.489362 (-3362 4658);
PAINT GREEN (-3362 4658);
FORCEPROP 2 LAST CDS_LIB mstr_standard
J 0
(-3300 4650);
DISPLAY 0.723404 (-3300 4650);
PAINT MONO (-3300 4650);
DISPLAY INVISIBLE (-3300 4650);
FORCEPROP 1 LAST BODY_TYPE PLUMBING
J 0
(-3300 4700);
DISPLAY 0.872340 (-3300 4700);
PAINT GREEN (-3300 4700);
DISPLAY INVISIBLE (-3300 4700);
FORCEPROP 1 LAST HDL_TAP TRUE
J 0
(-2975 4525);
DISPLAY 0.872340 (-2975 4525);
DISPLAY INVISIBLE (-2975 4525);
FORCEPROP 1 LAST PATH I198
J 0
(-3302 4650);
DISPLAY 0.872340 (-3302 4650);
PAINT GREEN (-3302 4650);
DISPLAY INVISIBLE (-3302 4650);
FORCEADD TAP..1
(-3300 4550);
FORCEPROP 3 LASTPIN (-3350 4550) SIG_NAME M_F_CPU1_SA_DQS_DN<8>
J 0
(-3340 4560);
DISPLAY 0.659574 (-3340 4560);
PAINT MONO (-3340 4560);
DISPLAY INVISIBLE (-3340 4560);
FORCEPROP 1 LASTPIN (-3350 4550) BN 8
J 0
(-3362 4558);
DISPLAY 0.489362 (-3362 4558);
PAINT GREEN (-3362 4558);
FORCEPROP 2 LAST CDS_LIB mstr_standard
J 0
(-3300 4550);
DISPLAY 0.723404 (-3300 4550);
PAINT MONO (-3300 4550);
DISPLAY INVISIBLE (-3300 4550);
FORCEPROP 1 LAST BODY_TYPE PLUMBING
J 0
(-3300 4600);
DISPLAY 0.872340 (-3300 4600);
PAINT GREEN (-3300 4600);
DISPLAY INVISIBLE (-3300 4600);
FORCEPROP 1 LAST HDL_TAP TRUE
J 0
(-2975 4425);
DISPLAY 0.872340 (-2975 4425);
DISPLAY INVISIBLE (-2975 4425);
FORCEPROP 1 LAST PATH I199
J 0
(-3302 4550);
DISPLAY 0.872340 (-3302 4550);
PAINT GREEN (-3302 4550);
DISPLAY INVISIBLE (-3302 4550);
FORCEADD OFFPAGE..5
(-8425 2075);
FORCEPROP 2 LAST $XR0 42 
J 0
(-8649 2075);
DISPLAY 0.638298 (-8649 2075);
PAINT MONO (-8649 2075);
FORCEPROP 2 LAST PATH I2
J 0
(-8625 2125);
DISPLAY 1.021277 (-8625 2125);
DISPLAY INVISIBLE (-8625 2125);
FORCEPROP 1 LAST COMMENT_BODY TRUE
J 0
(-8325 2000);
DISPLAY 0.872340 (-8325 2000);
PAINT GREEN (-8325 2000);
DISPLAY INVISIBLE (-8325 2000);
FORCEPROP 1 LAST OFFPAGE TRUE
J 0
(-8100 1950);
DISPLAY 0.872340 (-8100 1950);
PAINT GREEN (-8100 1950);
DISPLAY INVISIBLE (-8100 1950);
FORCEPROP 2 LAST CDS_LIB mstr_standard
J 0
(-8425 2075);
DISPLAY 0.808511 (-8425 2075);
DISPLAY INVISIBLE (-8425 2075);
FORCEADD OFFPAGE..1
(-8425 5575);
FORCEPROP 2 LAST $XR0 42 
J 0
(-8646 5575);
DISPLAY 0.638298 (-8646 5575);
PAINT MONO (-8646 5575);
FORCEPROP 2 LAST PATH I20
J 0
(-8675 5625);
DISPLAY 1.021277 (-8675 5625);
DISPLAY INVISIBLE (-8675 5625);
FORCEPROP 1 LAST COMMENT_BODY TRUE
J 0
(-8300 5475);
DISPLAY 0.872340 (-8300 5475);
PAINT GREEN (-8300 5475);
DISPLAY INVISIBLE (-8300 5475);
FORCEPROP 1 LAST OFFPAGE TRUE
J 0
(-8100 5450);
DISPLAY 0.872340 (-8100 5450);
PAINT GREEN (-8100 5450);
DISPLAY INVISIBLE (-8100 5450);
FORCEPROP 2 LAST CDS_LIB mstr_standard
J 0
(-8425 5575);
DISPLAY 0.723404 (-8425 5575);
PAINT MONO (-8425 5575);
DISPLAY INVISIBLE (-8425 5575);
FORCEADD TAP..1
(-3300 4450);
FORCEPROP 3 LASTPIN (-3350 4450) SIG_NAME M_F_CPU1_SA_DQS_DN<7>
J 0
(-3340 4460);
DISPLAY 0.659574 (-3340 4460);
PAINT MONO (-3340 4460);
DISPLAY INVISIBLE (-3340 4460);
FORCEPROP 1 LASTPIN (-3350 4450) BN 7
J 0
(-3362 4458);
DISPLAY 0.489362 (-3362 4458);
PAINT GREEN (-3362 4458);
FORCEPROP 2 LAST CDS_LIB mstr_standard
J 0
(-3300 4450);
DISPLAY 0.723404 (-3300 4450);
PAINT MONO (-3300 4450);
DISPLAY INVISIBLE (-3300 4450);
FORCEPROP 1 LAST BODY_TYPE PLUMBING
J 0
(-3300 4500);
DISPLAY 0.872340 (-3300 4500);
PAINT GREEN (-3300 4500);
DISPLAY INVISIBLE (-3300 4500);
FORCEPROP 1 LAST HDL_TAP TRUE
J 0
(-2975 4325);
DISPLAY 0.872340 (-2975 4325);
DISPLAY INVISIBLE (-2975 4325);
FORCEPROP 1 LAST PATH I200
J 0
(-3302 4450);
DISPLAY 0.872340 (-3302 4450);
PAINT GREEN (-3302 4450);
DISPLAY INVISIBLE (-3302 4450);
FORCEADD TAP..1
(-3500 4700);
FORCEPROP 3 LASTPIN (-3550 4700) SIG_NAME M_F_CPU1_SA_DQS_DP<9>
J 0
(-3540 4710);
DISPLAY 0.659574 (-3540 4710);
PAINT MONO (-3540 4710);
DISPLAY INVISIBLE (-3540 4710);
FORCEPROP 1 LASTPIN (-3550 4700) BN 9
J 0
(-3562 4708);
DISPLAY 0.489362 (-3562 4708);
PAINT GREEN (-3562 4708);
FORCEPROP 2 LAST CDS_LIB mstr_standard
J 0
(-3500 4700);
DISPLAY 0.723404 (-3500 4700);
PAINT MONO (-3500 4700);
DISPLAY INVISIBLE (-3500 4700);
FORCEPROP 1 LAST BODY_TYPE PLUMBING
J 0
(-3500 4750);
DISPLAY 0.872340 (-3500 4750);
PAINT GREEN (-3500 4750);
DISPLAY INVISIBLE (-3500 4750);
FORCEPROP 1 LAST HDL_TAP TRUE
J 0
(-3175 4575);
DISPLAY 0.872340 (-3175 4575);
DISPLAY INVISIBLE (-3175 4575);
FORCEPROP 1 LAST PATH I201
J 0
(-3502 4700);
DISPLAY 0.872340 (-3502 4700);
PAINT GREEN (-3502 4700);
DISPLAY INVISIBLE (-3502 4700);
FORCEADD TAP..1
(-3500 4600);
FORCEPROP 3 LASTPIN (-3550 4600) SIG_NAME M_F_CPU1_SA_DQS_DP<8>
J 0
(-3540 4610);
DISPLAY 0.659574 (-3540 4610);
PAINT MONO (-3540 4610);
DISPLAY INVISIBLE (-3540 4610);
FORCEPROP 1 LASTPIN (-3550 4600) BN 8
J 0
(-3562 4608);
DISPLAY 0.489362 (-3562 4608);
PAINT GREEN (-3562 4608);
FORCEPROP 2 LAST CDS_LIB mstr_standard
J 0
(-3500 4600);
DISPLAY 0.723404 (-3500 4600);
PAINT MONO (-3500 4600);
DISPLAY INVISIBLE (-3500 4600);
FORCEPROP 1 LAST BODY_TYPE PLUMBING
J 0
(-3500 4650);
DISPLAY 0.872340 (-3500 4650);
PAINT GREEN (-3500 4650);
DISPLAY INVISIBLE (-3500 4650);
FORCEPROP 1 LAST HDL_TAP TRUE
J 0
(-3175 4475);
DISPLAY 0.872340 (-3175 4475);
DISPLAY INVISIBLE (-3175 4475);
FORCEPROP 1 LAST PATH I202
J 0
(-3502 4600);
DISPLAY 0.872340 (-3502 4600);
PAINT GREEN (-3502 4600);
DISPLAY INVISIBLE (-3502 4600);
FORCEADD TAP..1
(-3500 4400);
FORCEPROP 3 LASTPIN (-3550 4400) SIG_NAME M_F_CPU1_SA_DQS_DP<6>
J 0
(-3540 4410);
DISPLAY 0.659574 (-3540 4410);
PAINT MONO (-3540 4410);
DISPLAY INVISIBLE (-3540 4410);
FORCEPROP 1 LASTPIN (-3550 4400) BN 6
J 0
(-3562 4408);
DISPLAY 0.489362 (-3562 4408);
PAINT GREEN (-3562 4408);
FORCEPROP 2 LAST CDS_LIB mstr_standard
J 0
(-3500 4400);
DISPLAY 0.723404 (-3500 4400);
PAINT MONO (-3500 4400);
DISPLAY INVISIBLE (-3500 4400);
FORCEPROP 1 LAST BODY_TYPE PLUMBING
J 0
(-3500 4450);
DISPLAY 0.872340 (-3500 4450);
PAINT GREEN (-3500 4450);
DISPLAY INVISIBLE (-3500 4450);
FORCEPROP 1 LAST HDL_TAP TRUE
J 0
(-3175 4275);
DISPLAY 0.872340 (-3175 4275);
DISPLAY INVISIBLE (-3175 4275);
FORCEPROP 1 LAST PATH I203
J 0
(-3502 4400);
DISPLAY 0.872340 (-3502 4400);
PAINT GREEN (-3502 4400);
DISPLAY INVISIBLE (-3502 4400);
FORCEADD TAP..1
(-3500 4500);
FORCEPROP 3 LASTPIN (-3550 4500) SIG_NAME M_F_CPU1_SA_DQS_DP<7>
J 0
(-3540 4510);
DISPLAY 0.659574 (-3540 4510);
PAINT MONO (-3540 4510);
DISPLAY INVISIBLE (-3540 4510);
FORCEPROP 1 LASTPIN (-3550 4500) BN 7
J 0
(-3562 4508);
DISPLAY 0.489362 (-3562 4508);
PAINT GREEN (-3562 4508);
FORCEPROP 2 LAST CDS_LIB mstr_standard
J 0
(-3500 4500);
DISPLAY 0.723404 (-3500 4500);
PAINT MONO (-3500 4500);
DISPLAY INVISIBLE (-3500 4500);
FORCEPROP 1 LAST BODY_TYPE PLUMBING
J 0
(-3500 4550);
DISPLAY 0.872340 (-3500 4550);
PAINT GREEN (-3500 4550);
DISPLAY INVISIBLE (-3500 4550);
FORCEPROP 1 LAST HDL_TAP TRUE
J 0
(-3175 4375);
DISPLAY 0.872340 (-3175 4375);
DISPLAY INVISIBLE (-3175 4375);
FORCEPROP 1 LAST PATH I204
J 0
(-3502 4500);
DISPLAY 0.872340 (-3502 4500);
PAINT GREEN (-3502 4500);
DISPLAY INVISIBLE (-3502 4500);
FORCEADD TAP..1
(-3300 4350);
FORCEPROP 3 LASTPIN (-3350 4350) SIG_NAME M_F_CPU1_SA_DQS_DN<6>
J 0
(-3340 4360);
DISPLAY 0.659574 (-3340 4360);
PAINT MONO (-3340 4360);
DISPLAY INVISIBLE (-3340 4360);
FORCEPROP 1 LASTPIN (-3350 4350) BN 6
J 0
(-3362 4358);
DISPLAY 0.489362 (-3362 4358);
PAINT GREEN (-3362 4358);
FORCEPROP 2 LAST CDS_LIB mstr_standard
J 0
(-3300 4350);
DISPLAY 0.723404 (-3300 4350);
PAINT MONO (-3300 4350);
DISPLAY INVISIBLE (-3300 4350);
FORCEPROP 1 LAST BODY_TYPE PLUMBING
J 0
(-3300 4400);
DISPLAY 0.872340 (-3300 4400);
PAINT GREEN (-3300 4400);
DISPLAY INVISIBLE (-3300 4400);
FORCEPROP 1 LAST HDL_TAP TRUE
J 0
(-2975 4225);
DISPLAY 0.872340 (-2975 4225);
DISPLAY INVISIBLE (-2975 4225);
FORCEPROP 1 LAST PATH I205
J 0
(-3302 4350);
DISPLAY 0.872340 (-3302 4350);
PAINT GREEN (-3302 4350);
DISPLAY INVISIBLE (-3302 4350);
FORCEADD TAP..1
(-3300 4250);
FORCEPROP 3 LASTPIN (-3350 4250) SIG_NAME M_F_CPU1_SA_DQS_DN<5>
J 0
(-3340 4260);
DISPLAY 0.659574 (-3340 4260);
PAINT MONO (-3340 4260);
DISPLAY INVISIBLE (-3340 4260);
FORCEPROP 1 LASTPIN (-3350 4250) BN 5
J 0
(-3362 4258);
DISPLAY 0.489362 (-3362 4258);
PAINT GREEN (-3362 4258);
FORCEPROP 2 LAST CDS_LIB mstr_standard
J 0
(-3300 4250);
DISPLAY 0.723404 (-3300 4250);
PAINT MONO (-3300 4250);
DISPLAY INVISIBLE (-3300 4250);
FORCEPROP 1 LAST BODY_TYPE PLUMBING
J 0
(-3300 4300);
DISPLAY 0.872340 (-3300 4300);
PAINT GREEN (-3300 4300);
DISPLAY INVISIBLE (-3300 4300);
FORCEPROP 1 LAST HDL_TAP TRUE
J 0
(-2975 4125);
DISPLAY 0.872340 (-2975 4125);
DISPLAY INVISIBLE (-2975 4125);
FORCEPROP 1 LAST PATH I206
J 0
(-3302 4250);
DISPLAY 0.872340 (-3302 4250);
PAINT GREEN (-3302 4250);
DISPLAY INVISIBLE (-3302 4250);
FORCEADD TAP..1
(-3300 4150);
FORCEPROP 3 LASTPIN (-3350 4150) SIG_NAME M_F_CPU1_SA_DQS_DN<4>
J 0
(-3340 4160);
DISPLAY 0.659574 (-3340 4160);
PAINT MONO (-3340 4160);
DISPLAY INVISIBLE (-3340 4160);
FORCEPROP 1 LASTPIN (-3350 4150) BN 4
J 0
(-3362 4158);
DISPLAY 0.489362 (-3362 4158);
PAINT GREEN (-3362 4158);
FORCEPROP 2 LAST CDS_LIB mstr_standard
J 0
(-3300 4150);
DISPLAY 0.723404 (-3300 4150);
PAINT MONO (-3300 4150);
DISPLAY INVISIBLE (-3300 4150);
FORCEPROP 1 LAST BODY_TYPE PLUMBING
J 0
(-3300 4200);
DISPLAY 0.872340 (-3300 4200);
PAINT GREEN (-3300 4200);
DISPLAY INVISIBLE (-3300 4200);
FORCEPROP 1 LAST HDL_TAP TRUE
J 0
(-2975 4025);
DISPLAY 0.872340 (-2975 4025);
DISPLAY INVISIBLE (-2975 4025);
FORCEPROP 1 LAST PATH I207
J 0
(-3302 4150);
DISPLAY 0.872340 (-3302 4150);
PAINT GREEN (-3302 4150);
DISPLAY INVISIBLE (-3302 4150);
FORCEADD TAP..1
(-3300 4050);
FORCEPROP 3 LASTPIN (-3350 4050) SIG_NAME M_F_CPU1_SA_DQS_DN<3>
J 0
(-3340 4060);
DISPLAY 0.659574 (-3340 4060);
PAINT MONO (-3340 4060);
DISPLAY INVISIBLE (-3340 4060);
FORCEPROP 1 LASTPIN (-3350 4050) BN 3
J 0
(-3362 4058);
DISPLAY 0.489362 (-3362 4058);
PAINT GREEN (-3362 4058);
FORCEPROP 2 LAST CDS_LIB mstr_standard
J 0
(-3300 4050);
DISPLAY 0.723404 (-3300 4050);
PAINT MONO (-3300 4050);
DISPLAY INVISIBLE (-3300 4050);
FORCEPROP 1 LAST BODY_TYPE PLUMBING
J 0
(-3300 4100);
DISPLAY 0.872340 (-3300 4100);
PAINT GREEN (-3300 4100);
DISPLAY INVISIBLE (-3300 4100);
FORCEPROP 1 LAST HDL_TAP TRUE
J 0
(-2975 3925);
DISPLAY 0.872340 (-2975 3925);
DISPLAY INVISIBLE (-2975 3925);
FORCEPROP 1 LAST PATH I208
J 0
(-3302 4050);
DISPLAY 0.872340 (-3302 4050);
PAINT GREEN (-3302 4050);
DISPLAY INVISIBLE (-3302 4050);
FORCEADD TAP..1
(-3300 3950);
FORCEPROP 3 LASTPIN (-3350 3950) SIG_NAME M_F_CPU1_SA_DQS_DN<2>
J 0
(-3340 3960);
DISPLAY 0.659574 (-3340 3960);
PAINT MONO (-3340 3960);
DISPLAY INVISIBLE (-3340 3960);
FORCEPROP 1 LASTPIN (-3350 3950) BN 2
J 0
(-3362 3958);
DISPLAY 0.489362 (-3362 3958);
PAINT GREEN (-3362 3958);
FORCEPROP 2 LAST CDS_LIB mstr_standard
J 0
(-3300 3950);
DISPLAY 0.723404 (-3300 3950);
PAINT MONO (-3300 3950);
DISPLAY INVISIBLE (-3300 3950);
FORCEPROP 1 LAST BODY_TYPE PLUMBING
J 0
(-3300 4000);
DISPLAY 0.872340 (-3300 4000);
PAINT GREEN (-3300 4000);
DISPLAY INVISIBLE (-3300 4000);
FORCEPROP 1 LAST HDL_TAP TRUE
J 0
(-2975 3825);
DISPLAY 0.872340 (-2975 3825);
DISPLAY INVISIBLE (-2975 3825);
FORCEPROP 1 LAST PATH I209
J 0
(-3302 3950);
DISPLAY 0.872340 (-3302 3950);
PAINT GREEN (-3302 3950);
DISPLAY INVISIBLE (-3302 3950);
FORCEADD OFFPAGE..1
(-8425 5175);
FORCEPROP 2 LAST $XR0 42 
J 0
(-8646 5175);
DISPLAY 0.638298 (-8646 5175);
PAINT MONO (-8646 5175);
FORCEPROP 2 LAST PATH I21
J 0
(-8675 5225);
DISPLAY 1.021277 (-8675 5225);
DISPLAY INVISIBLE (-8675 5225);
FORCEPROP 1 LAST COMMENT_BODY TRUE
J 0
(-8300 5075);
DISPLAY 0.872340 (-8300 5075);
PAINT GREEN (-8300 5075);
DISPLAY INVISIBLE (-8300 5075);
FORCEPROP 1 LAST OFFPAGE TRUE
J 0
(-8100 5050);
DISPLAY 0.872340 (-8100 5050);
PAINT GREEN (-8100 5050);
DISPLAY INVISIBLE (-8100 5050);
FORCEPROP 2 LAST CDS_LIB mstr_standard
J 0
(-8425 5175);
DISPLAY 0.723404 (-8425 5175);
PAINT MONO (-8425 5175);
DISPLAY INVISIBLE (-8425 5175);
FORCEADD TAP..1
(-3500 4300);
FORCEPROP 3 LASTPIN (-3550 4300) SIG_NAME M_F_CPU1_SA_DQS_DP<5>
J 0
(-3540 4310);
DISPLAY 0.659574 (-3540 4310);
PAINT MONO (-3540 4310);
DISPLAY INVISIBLE (-3540 4310);
FORCEPROP 1 LASTPIN (-3550 4300) BN 5
J 0
(-3562 4308);
DISPLAY 0.489362 (-3562 4308);
PAINT GREEN (-3562 4308);
FORCEPROP 2 LAST CDS_LIB mstr_standard
J 0
(-3500 4300);
DISPLAY 0.723404 (-3500 4300);
PAINT MONO (-3500 4300);
DISPLAY INVISIBLE (-3500 4300);
FORCEPROP 1 LAST BODY_TYPE PLUMBING
J 0
(-3500 4350);
DISPLAY 0.872340 (-3500 4350);
PAINT GREEN (-3500 4350);
DISPLAY INVISIBLE (-3500 4350);
FORCEPROP 1 LAST HDL_TAP TRUE
J 0
(-3175 4175);
DISPLAY 0.872340 (-3175 4175);
DISPLAY INVISIBLE (-3175 4175);
FORCEPROP 1 LAST PATH I210
J 0
(-3502 4300);
DISPLAY 0.872340 (-3502 4300);
PAINT GREEN (-3502 4300);
DISPLAY INVISIBLE (-3502 4300);
FORCEADD TAP..1
(-3500 3900);
FORCEPROP 3 LASTPIN (-3550 3900) SIG_NAME M_F_CPU1_SA_DQS_DP<1>
J 0
(-3540 3910);
DISPLAY 0.659574 (-3540 3910);
PAINT MONO (-3540 3910);
DISPLAY INVISIBLE (-3540 3910);
FORCEPROP 1 LASTPIN (-3550 3900) BN 1
J 0
(-3562 3908);
DISPLAY 0.489362 (-3562 3908);
PAINT GREEN (-3562 3908);
FORCEPROP 2 LAST CDS_LIB mstr_standard
J 0
(-3500 3900);
DISPLAY 0.723404 (-3500 3900);
PAINT MONO (-3500 3900);
DISPLAY INVISIBLE (-3500 3900);
FORCEPROP 1 LAST BODY_TYPE PLUMBING
J 0
(-3500 3950);
DISPLAY 0.872340 (-3500 3950);
PAINT GREEN (-3500 3950);
DISPLAY INVISIBLE (-3500 3950);
FORCEPROP 1 LAST HDL_TAP TRUE
J 0
(-3175 3775);
DISPLAY 0.872340 (-3175 3775);
DISPLAY INVISIBLE (-3175 3775);
FORCEPROP 1 LAST PATH I211
J 0
(-3502 3900);
DISPLAY 0.872340 (-3502 3900);
PAINT GREEN (-3502 3900);
DISPLAY INVISIBLE (-3502 3900);
FORCEADD TAP..1
(-3500 4100);
FORCEPROP 3 LASTPIN (-3550 4100) SIG_NAME M_F_CPU1_SA_DQS_DP<3>
J 0
(-3540 4110);
DISPLAY 0.659574 (-3540 4110);
PAINT MONO (-3540 4110);
DISPLAY INVISIBLE (-3540 4110);
FORCEPROP 1 LASTPIN (-3550 4100) BN 3
J 0
(-3562 4108);
DISPLAY 0.489362 (-3562 4108);
PAINT GREEN (-3562 4108);
FORCEPROP 2 LAST CDS_LIB mstr_standard
J 0
(-3500 4100);
DISPLAY 0.723404 (-3500 4100);
PAINT MONO (-3500 4100);
DISPLAY INVISIBLE (-3500 4100);
FORCEPROP 1 LAST BODY_TYPE PLUMBING
J 0
(-3500 4150);
DISPLAY 0.872340 (-3500 4150);
PAINT GREEN (-3500 4150);
DISPLAY INVISIBLE (-3500 4150);
FORCEPROP 1 LAST HDL_TAP TRUE
J 0
(-3175 3975);
DISPLAY 0.872340 (-3175 3975);
DISPLAY INVISIBLE (-3175 3975);
FORCEPROP 1 LAST PATH I212
J 0
(-3502 4100);
DISPLAY 0.872340 (-3502 4100);
PAINT GREEN (-3502 4100);
DISPLAY INVISIBLE (-3502 4100);
FORCEADD TAP..1
(-3300 3750);
FORCEPROP 3 LASTPIN (-3350 3750) SIG_NAME M_F_CPU1_SA_DQS_DN<0>
J 0
(-3340 3760);
DISPLAY 0.659574 (-3340 3760);
PAINT MONO (-3340 3760);
DISPLAY INVISIBLE (-3340 3760);
FORCEPROP 1 LASTPIN (-3350 3750) BN 0
J 0
(-3362 3758);
DISPLAY 0.489362 (-3362 3758);
PAINT GREEN (-3362 3758);
FORCEPROP 2 LAST CDS_LIB mstr_standard
J 0
(-3300 3750);
DISPLAY 0.723404 (-3300 3750);
PAINT MONO (-3300 3750);
DISPLAY INVISIBLE (-3300 3750);
FORCEPROP 1 LAST BODY_TYPE PLUMBING
J 0
(-3300 3800);
DISPLAY 0.872340 (-3300 3800);
PAINT GREEN (-3300 3800);
DISPLAY INVISIBLE (-3300 3800);
FORCEPROP 1 LAST HDL_TAP TRUE
J 0
(-2975 3625);
DISPLAY 0.872340 (-2975 3625);
DISPLAY INVISIBLE (-2975 3625);
FORCEPROP 1 LAST PATH I213
J 0
(-3302 3750);
DISPLAY 0.872340 (-3302 3750);
PAINT GREEN (-3302 3750);
DISPLAY INVISIBLE (-3302 3750);
FORCEADD TAP..1
(-3300 3850);
FORCEPROP 3 LASTPIN (-3350 3850) SIG_NAME M_F_CPU1_SA_DQS_DN<1>
J 0
(-3340 3860);
DISPLAY 0.659574 (-3340 3860);
PAINT MONO (-3340 3860);
DISPLAY INVISIBLE (-3340 3860);
FORCEPROP 1 LASTPIN (-3350 3850) BN 1
J 0
(-3362 3858);
DISPLAY 0.489362 (-3362 3858);
PAINT GREEN (-3362 3858);
FORCEPROP 2 LAST CDS_LIB mstr_standard
J 0
(-3300 3850);
DISPLAY 0.723404 (-3300 3850);
PAINT MONO (-3300 3850);
DISPLAY INVISIBLE (-3300 3850);
FORCEPROP 1 LAST BODY_TYPE PLUMBING
J 0
(-3300 3900);
DISPLAY 0.872340 (-3300 3900);
PAINT GREEN (-3300 3900);
DISPLAY INVISIBLE (-3300 3900);
FORCEPROP 1 LAST HDL_TAP TRUE
J 0
(-2975 3725);
DISPLAY 0.872340 (-2975 3725);
DISPLAY INVISIBLE (-2975 3725);
FORCEPROP 1 LAST PATH I214
J 0
(-3302 3850);
DISPLAY 0.872340 (-3302 3850);
PAINT GREEN (-3302 3850);
DISPLAY INVISIBLE (-3302 3850);
FORCEADD TAP..1
(-3300 3600);
FORCEPROP 3 LASTPIN (-3350 3600) SIG_NAME M_F_CPU1_SB_DQS_DN<9>
J 0
(-3340 3610);
DISPLAY 0.659574 (-3340 3610);
PAINT MONO (-3340 3610);
DISPLAY INVISIBLE (-3340 3610);
FORCEPROP 1 LASTPIN (-3350 3600) BN 9
J 0
(-3362 3608);
DISPLAY 0.489362 (-3362 3608);
PAINT GREEN (-3362 3608);
FORCEPROP 2 LAST CDS_LIB mstr_standard
J 0
(-3300 3600);
DISPLAY 0.723404 (-3300 3600);
PAINT MONO (-3300 3600);
DISPLAY INVISIBLE (-3300 3600);
FORCEPROP 1 LAST BODY_TYPE PLUMBING
J 0
(-3300 3650);
DISPLAY 0.872340 (-3300 3650);
PAINT GREEN (-3300 3650);
DISPLAY INVISIBLE (-3300 3650);
FORCEPROP 1 LAST HDL_TAP TRUE
J 0
(-2975 3475);
DISPLAY 0.872340 (-2975 3475);
DISPLAY INVISIBLE (-2975 3475);
FORCEPROP 1 LAST PATH I215
J 0
(-3302 3600);
DISPLAY 0.872340 (-3302 3600);
PAINT GREEN (-3302 3600);
DISPLAY INVISIBLE (-3302 3600);
FORCEADD TAP..1
(-3300 3500);
FORCEPROP 3 LASTPIN (-3350 3500) SIG_NAME M_F_CPU1_SB_DQS_DN<8>
J 0
(-3340 3510);
DISPLAY 0.659574 (-3340 3510);
PAINT MONO (-3340 3510);
DISPLAY INVISIBLE (-3340 3510);
FORCEPROP 1 LASTPIN (-3350 3500) BN 8
J 0
(-3362 3508);
DISPLAY 0.489362 (-3362 3508);
PAINT GREEN (-3362 3508);
FORCEPROP 2 LAST CDS_LIB mstr_standard
J 0
(-3300 3500);
DISPLAY 0.723404 (-3300 3500);
PAINT MONO (-3300 3500);
DISPLAY INVISIBLE (-3300 3500);
FORCEPROP 1 LAST BODY_TYPE PLUMBING
J 0
(-3300 3550);
DISPLAY 0.872340 (-3300 3550);
PAINT GREEN (-3300 3550);
DISPLAY INVISIBLE (-3300 3550);
FORCEPROP 1 LAST HDL_TAP TRUE
J 0
(-2975 3375);
DISPLAY 0.872340 (-2975 3375);
DISPLAY INVISIBLE (-2975 3375);
FORCEPROP 1 LAST PATH I216
J 0
(-3302 3500);
DISPLAY 0.872340 (-3302 3500);
PAINT GREEN (-3302 3500);
DISPLAY INVISIBLE (-3302 3500);
FORCEADD TAP..1
(-3300 3400);
FORCEPROP 3 LASTPIN (-3350 3400) SIG_NAME M_F_CPU1_SB_DQS_DN<7>
J 0
(-3340 3410);
DISPLAY 0.659574 (-3340 3410);
PAINT MONO (-3340 3410);
DISPLAY INVISIBLE (-3340 3410);
FORCEPROP 1 LASTPIN (-3350 3400) BN 7
J 0
(-3362 3408);
DISPLAY 0.489362 (-3362 3408);
PAINT GREEN (-3362 3408);
FORCEPROP 2 LAST CDS_LIB mstr_standard
J 0
(-3300 3400);
DISPLAY 0.723404 (-3300 3400);
PAINT MONO (-3300 3400);
DISPLAY INVISIBLE (-3300 3400);
FORCEPROP 1 LAST BODY_TYPE PLUMBING
J 0
(-3300 3450);
DISPLAY 0.872340 (-3300 3450);
PAINT GREEN (-3300 3450);
DISPLAY INVISIBLE (-3300 3450);
FORCEPROP 1 LAST HDL_TAP TRUE
J 0
(-2975 3275);
DISPLAY 0.872340 (-2975 3275);
DISPLAY INVISIBLE (-2975 3275);
FORCEPROP 1 LAST PATH I217
J 0
(-3302 3400);
DISPLAY 0.872340 (-3302 3400);
PAINT GREEN (-3302 3400);
DISPLAY INVISIBLE (-3302 3400);
FORCEADD TAP..1
(-3500 3650);
FORCEPROP 3 LASTPIN (-3550 3650) SIG_NAME M_F_CPU1_SB_DQS_DP<9>
J 0
(-3540 3660);
DISPLAY 0.659574 (-3540 3660);
PAINT MONO (-3540 3660);
DISPLAY INVISIBLE (-3540 3660);
FORCEPROP 1 LASTPIN (-3550 3650) BN 9
J 0
(-3562 3658);
DISPLAY 0.489362 (-3562 3658);
PAINT GREEN (-3562 3658);
FORCEPROP 2 LAST CDS_LIB mstr_standard
J 0
(-3500 3650);
DISPLAY 0.723404 (-3500 3650);
PAINT MONO (-3500 3650);
DISPLAY INVISIBLE (-3500 3650);
FORCEPROP 1 LAST BODY_TYPE PLUMBING
J 0
(-3500 3700);
DISPLAY 0.872340 (-3500 3700);
PAINT GREEN (-3500 3700);
DISPLAY INVISIBLE (-3500 3700);
FORCEPROP 1 LAST HDL_TAP TRUE
J 0
(-3175 3525);
DISPLAY 0.872340 (-3175 3525);
DISPLAY INVISIBLE (-3175 3525);
FORCEPROP 1 LAST PATH I218
J 0
(-3502 3650);
DISPLAY 0.872340 (-3502 3650);
PAINT GREEN (-3502 3650);
DISPLAY INVISIBLE (-3502 3650);
FORCEADD TAP..1
(-3500 3800);
FORCEPROP 3 LASTPIN (-3550 3800) SIG_NAME M_F_CPU1_SA_DQS_DP<0>
J 0
(-3540 3810);
DISPLAY 0.659574 (-3540 3810);
PAINT MONO (-3540 3810);
DISPLAY INVISIBLE (-3540 3810);
FORCEPROP 1 LASTPIN (-3550 3800) BN 0
J 0
(-3562 3808);
DISPLAY 0.489362 (-3562 3808);
PAINT GREEN (-3562 3808);
FORCEPROP 2 LAST CDS_LIB mstr_standard
J 0
(-3500 3800);
DISPLAY 0.723404 (-3500 3800);
PAINT MONO (-3500 3800);
DISPLAY INVISIBLE (-3500 3800);
FORCEPROP 1 LAST BODY_TYPE PLUMBING
J 0
(-3500 3850);
DISPLAY 0.872340 (-3500 3850);
PAINT GREEN (-3500 3850);
DISPLAY INVISIBLE (-3500 3850);
FORCEPROP 1 LAST HDL_TAP TRUE
J 0
(-3175 3675);
DISPLAY 0.872340 (-3175 3675);
DISPLAY INVISIBLE (-3175 3675);
FORCEPROP 1 LAST PATH I219
J 0
(-3502 3800);
DISPLAY 0.872340 (-3502 3800);
PAINT GREEN (-3502 3800);
DISPLAY INVISIBLE (-3502 3800);
FORCEADD SCONN288_DDR506112002KQ..1
(-6975 3775);
FORCEPROP 1 LAST LOCATION J33
J 0
(-7425 5850);
DISPLAY 0.468085 (-7425 5850);
PAINT SKYBLUE (-7425 5850);
FORCEPROP 0 LAST $SEC 1
J 0
(-7425 6000);
DISPLAY 0.680851 (-7425 6000);
PAINT MONO (-7425 6000);
DISPLAY INVISIBLE (-7425 6000);
FORCEPROP 2 LAST CDS_SEC 1
J 0
(-7425 6000);
DISPLAY 1.021277 (-7425 6000);
DISPLAY INVISIBLE (-7425 6000);
FORCEPROP 0 LASTPIN (-7575 3175) $PN 62
J 2
(-7585 3185);
DISPLAY 0.680851 (-7585 3185);
PAINT MONO (-7585 3185);
FORCEPROP 0 LASTPIN (-7575 5225) $PN 66
J 2
(-7585 5235);
DISPLAY 0.680851 (-7585 5235);
PAINT MONO (-7585 5235);
FORCEPROP 0 LASTPIN (-7575 4825) $PN 76
J 2
(-7585 4835);
DISPLAY 0.680851 (-7585 4835);
PAINT MONO (-7585 4835);
FORCEPROP 0 LASTPIN (-7575 5275) $PN 211
J 2
(-7585 5285);
DISPLAY 0.680851 (-7585 5285);
PAINT MONO (-7585 5285);
FORCEPROP 0 LASTPIN (-7575 4875) $PN 221
J 2
(-7585 4885);
DISPLAY 0.680851 (-7585 4885);
PAINT MONO (-7585 4885);
FORCEPROP 0 LASTPIN (-7575 5325) $PN 68
J 2
(-7585 5335);
DISPLAY 0.680851 (-7585 5335);
PAINT MONO (-7585 5335);
FORCEPROP 0 LASTPIN (-7575 4925) $PN 78
J 2
(-7585 4935);
DISPLAY 0.680851 (-7585 4935);
PAINT MONO (-7585 4935);
FORCEPROP 0 LASTPIN (-7575 5375) $PN 213
J 2
(-7585 5385);
DISPLAY 0.680851 (-7585 5385);
PAINT MONO (-7585 5385);
FORCEPROP 0 LASTPIN (-7575 4975) $PN 223
J 2
(-7585 4985);
DISPLAY 0.680851 (-7585 4985);
PAINT MONO (-7585 4985);
FORCEPROP 0 LASTPIN (-7575 5425) $PN 70
J 2
(-7585 5435);
DISPLAY 0.680851 (-7585 5435);
PAINT MONO (-7585 5435);
FORCEPROP 0 LASTPIN (-7575 5025) $PN 80
J 2
(-7585 5035);
DISPLAY 0.680851 (-7585 5035);
PAINT MONO (-7585 5035);
FORCEPROP 0 LASTPIN (-7575 5475) $PN 215
J 2
(-7585 5485);
DISPLAY 0.680851 (-7585 5485);
PAINT MONO (-7585 5485);
FORCEPROP 0 LASTPIN (-7575 5075) $PN 225
J 2
(-7585 5085);
DISPLAY 0.680851 (-7585 5085);
PAINT MONO (-7585 5085);
FORCEPROP 0 LASTPIN (-7575 5525) $PN 72
J 2
(-7585 5535);
DISPLAY 0.680851 (-7585 5535);
PAINT MONO (-7585 5535);
FORCEPROP 0 LASTPIN (-7575 5125) $PN 82
J 2
(-7585 5135);
DISPLAY 0.680851 (-7585 5135);
PAINT MONO (-7585 5135);
FORCEPROP 0 LASTPIN (-7575 3775) $PN 51
J 2
(-7585 3785);
DISPLAY 0.680851 (-7585 3785);
PAINT MONO (-7585 3785);
FORCEPROP 0 LASTPIN (-7575 3325) $PN 96
J 2
(-7585 3335);
DISPLAY 0.680851 (-7585 3335);
PAINT MONO (-7585 3335);
FORCEPROP 0 LASTPIN (-7575 3825) $PN 53
J 2
(-7585 3835);
DISPLAY 0.680851 (-7585 3835);
PAINT MONO (-7585 3835);
FORCEPROP 0 LASTPIN (-7575 3375) $PN 98
J 2
(-7585 3385);
DISPLAY 0.680851 (-7585 3385);
PAINT MONO (-7585 3385);
FORCEPROP 0 LASTPIN (-7575 3875) $PN 196
J 2
(-7585 3885);
DISPLAY 0.680851 (-7585 3885);
PAINT MONO (-7585 3885);
FORCEPROP 0 LASTPIN (-7575 3425) $PN 241
J 2
(-7585 3435);
DISPLAY 0.680851 (-7585 3435);
PAINT MONO (-7585 3435);
FORCEPROP 0 LASTPIN (-7575 3925) $PN 198
J 2
(-7585 3935);
DISPLAY 0.680851 (-7585 3935);
PAINT MONO (-7585 3935);
FORCEPROP 0 LASTPIN (-7575 3475) $PN 243
J 2
(-7585 3485);
DISPLAY 0.680851 (-7585 3485);
PAINT MONO (-7585 3485);
FORCEPROP 0 LASTPIN (-7575 3975) $PN 58
J 2
(-7585 3985);
DISPLAY 0.680851 (-7585 3985);
PAINT MONO (-7585 3985);
FORCEPROP 0 LASTPIN (-7575 3525) $PN 89
J 2
(-7585 3535);
DISPLAY 0.680851 (-7585 3535);
PAINT MONO (-7585 3535);
FORCEPROP 0 LASTPIN (-7575 4025) $PN 60
J 2
(-7585 4035);
DISPLAY 0.680851 (-7585 4035);
PAINT MONO (-7585 4035);
FORCEPROP 0 LASTPIN (-7575 3575) $PN 91
J 2
(-7585 3585);
DISPLAY 0.680851 (-7585 3585);
PAINT MONO (-7585 3585);
FORCEPROP 0 LASTPIN (-7575 4075) $PN 203
J 2
(-7585 4085);
DISPLAY 0.680851 (-7585 4085);
PAINT MONO (-7585 4085);
FORCEPROP 0 LASTPIN (-7575 3625) $PN 234
J 2
(-7585 3635);
DISPLAY 0.680851 (-7585 3635);
PAINT MONO (-7585 3635);
FORCEPROP 0 LASTPIN (-7575 4125) $PN 205
J 2
(-7585 4135);
DISPLAY 0.680851 (-7585 4135);
PAINT MONO (-7585 4135);
FORCEPROP 0 LASTPIN (-7575 3675) $PN 236
J 2
(-7585 3685);
DISPLAY 0.680851 (-7585 3685);
PAINT MONO (-7585 3685);
FORCEPROP 0 LASTPIN (-7575 4225) $PN 218
J 2
(-7585 4235);
DISPLAY 0.680851 (-7585 4235);
PAINT MONO (-7585 4235);
FORCEPROP 0 LASTPIN (-7575 4275) $PN 217
J 2
(-7585 4285);
DISPLAY 0.680851 (-7585 4285);
PAINT MONO (-7585 4285);
FORCEPROP 0 LASTPIN (-7575 4525) $PN 64
J 2
(-7585 4535);
DISPLAY 0.680851 (-7585 4535);
PAINT MONO (-7585 4535);
FORCEPROP 0 LASTPIN (-7575 4375) $PN 84
J 2
(-7585 4385);
DISPLAY 0.680851 (-7585 4385);
PAINT MONO (-7585 4385);
FORCEPROP 0 LASTPIN (-7575 4575) $PN 209
J 2
(-7585 4585);
DISPLAY 0.680851 (-7585 4585);
PAINT MONO (-7585 4585);
FORCEPROP 0 LASTPIN (-7575 4425) $PN 229
J 2
(-7585 4435);
DISPLAY 0.680851 (-7585 4435);
PAINT MONO (-7585 4435);
FORCEPROP 0 LASTPIN (-6375 3975) $PN 7
J 0
(-6365 3985);
DISPLAY 0.680851 (-6365 3985);
PAINT MONO (-6365 3985);
FORCEPROP 0 LASTPIN (-6375 2325) $PN 100
J 0
(-6365 2335);
DISPLAY 0.680851 (-6365 2335);
PAINT MONO (-6365 2335);
FORCEPROP 0 LASTPIN (-6375 4025) $PN 9
J 0
(-6365 4035);
DISPLAY 0.680851 (-6365 4035);
PAINT MONO (-6365 4035);
FORCEPROP 0 LASTPIN (-6375 2375) $PN 102
J 0
(-6365 2385);
DISPLAY 0.680851 (-6365 2385);
PAINT MONO (-6365 2385);
FORCEPROP 0 LASTPIN (-6375 4075) $PN 152
J 0
(-6365 4085);
DISPLAY 0.680851 (-6365 4085);
PAINT MONO (-6365 4085);
FORCEPROP 0 LASTPIN (-6375 2425) $PN 245
J 0
(-6365 2435);
DISPLAY 0.680851 (-6365 2435);
PAINT MONO (-6365 2435);
FORCEPROP 0 LASTPIN (-6375 4125) $PN 154
J 0
(-6365 4135);
DISPLAY 0.680851 (-6365 4135);
PAINT MONO (-6365 4135);
FORCEPROP 0 LASTPIN (-6375 2475) $PN 247
J 0
(-6365 2485);
DISPLAY 0.680851 (-6365 2485);
PAINT MONO (-6365 2485);
FORCEPROP 0 LASTPIN (-6375 4175) $PN 14
J 0
(-6365 4185);
DISPLAY 0.680851 (-6365 4185);
PAINT MONO (-6365 4185);
FORCEPROP 0 LASTPIN (-6375 2525) $PN 107
J 0
(-6365 2535);
DISPLAY 0.680851 (-6365 2535);
PAINT MONO (-6365 2535);
FORCEPROP 0 LASTPIN (-6375 4225) $PN 16
J 0
(-6365 4235);
DISPLAY 0.680851 (-6365 4235);
PAINT MONO (-6365 4235);
FORCEPROP 0 LASTPIN (-6375 2575) $PN 109
J 0
(-6365 2585);
DISPLAY 0.680851 (-6365 2585);
PAINT MONO (-6365 2585);
FORCEPROP 0 LASTPIN (-6375 4275) $PN 159
J 0
(-6365 4285);
DISPLAY 0.680851 (-6365 4285);
PAINT MONO (-6365 4285);
FORCEPROP 0 LASTPIN (-6375 2625) $PN 252
J 0
(-6365 2635);
DISPLAY 0.680851 (-6365 2635);
PAINT MONO (-6365 2635);
FORCEPROP 0 LASTPIN (-6375 4325) $PN 161
J 0
(-6365 4335);
DISPLAY 0.680851 (-6365 4335);
PAINT MONO (-6365 4335);
FORCEPROP 0 LASTPIN (-6375 2675) $PN 254
J 0
(-6365 2685);
DISPLAY 0.680851 (-6365 2685);
PAINT MONO (-6365 2685);
FORCEPROP 0 LASTPIN (-6375 4375) $PN 18
J 0
(-6365 4385);
DISPLAY 0.680851 (-6365 4385);
PAINT MONO (-6365 4385);
FORCEPROP 0 LASTPIN (-6375 2725) $PN 111
J 0
(-6365 2735);
DISPLAY 0.680851 (-6365 2735);
PAINT MONO (-6365 2735);
FORCEPROP 0 LASTPIN (-6375 4425) $PN 20
J 0
(-6365 4435);
DISPLAY 0.680851 (-6365 4435);
PAINT MONO (-6365 4435);
FORCEPROP 0 LASTPIN (-6375 2775) $PN 113
J 0
(-6365 2785);
DISPLAY 0.680851 (-6365 2785);
PAINT MONO (-6365 2785);
FORCEPROP 0 LASTPIN (-6375 4475) $PN 163
J 0
(-6365 4485);
DISPLAY 0.680851 (-6365 4485);
PAINT MONO (-6365 4485);
FORCEPROP 0 LASTPIN (-6375 2825) $PN 256
J 0
(-6365 2835);
DISPLAY 0.680851 (-6365 2835);
PAINT MONO (-6365 2835);
FORCEPROP 0 LASTPIN (-6375 4525) $PN 165
J 0
(-6365 4535);
DISPLAY 0.680851 (-6365 4535);
PAINT MONO (-6365 4535);
FORCEPROP 0 LASTPIN (-6375 2875) $PN 258
J 0
(-6365 2885);
DISPLAY 0.680851 (-6365 2885);
PAINT MONO (-6365 2885);
FORCEPROP 0 LASTPIN (-6375 4575) $PN 25
J 0
(-6365 4585);
DISPLAY 0.680851 (-6365 4585);
PAINT MONO (-6365 4585);
FORCEPROP 0 LASTPIN (-6375 2925) $PN 118
J 0
(-6365 2935);
DISPLAY 0.680851 (-6365 2935);
PAINT MONO (-6365 2935);
FORCEPROP 0 LASTPIN (-6375 4625) $PN 27
J 0
(-6365 4635);
DISPLAY 0.680851 (-6365 4635);
PAINT MONO (-6365 4635);
FORCEPROP 0 LASTPIN (-6375 2975) $PN 120
J 0
(-6365 2985);
DISPLAY 0.680851 (-6365 2985);
PAINT MONO (-6365 2985);
FORCEPROP 0 LASTPIN (-6375 4675) $PN 170
J 0
(-6365 4685);
DISPLAY 0.680851 (-6365 4685);
PAINT MONO (-6365 4685);
FORCEPROP 0 LASTPIN (-6375 3025) $PN 263
J 0
(-6365 3035);
DISPLAY 0.680851 (-6365 3035);
PAINT MONO (-6365 3035);
FORCEPROP 0 LASTPIN (-6375 4725) $PN 172
J 0
(-6365 4735);
DISPLAY 0.680851 (-6365 4735);
PAINT MONO (-6365 4735);
FORCEPROP 0 LASTPIN (-6375 3075) $PN 265
J 0
(-6365 3085);
DISPLAY 0.680851 (-6365 3085);
PAINT MONO (-6365 3085);
FORCEPROP 0 LASTPIN (-6375 4775) $PN 29
J 0
(-6365 4785);
DISPLAY 0.680851 (-6365 4785);
PAINT MONO (-6365 4785);
FORCEPROP 0 LASTPIN (-6375 3125) $PN 122
J 0
(-6365 3135);
DISPLAY 0.680851 (-6365 3135);
PAINT MONO (-6365 3135);
FORCEPROP 0 LASTPIN (-6375 4825) $PN 31
J 0
(-6365 4835);
DISPLAY 0.680851 (-6365 4835);
PAINT MONO (-6365 4835);
FORCEPROP 0 LASTPIN (-6375 3175) $PN 124
J 0
(-6365 3185);
DISPLAY 0.680851 (-6365 3185);
PAINT MONO (-6365 3185);
FORCEPROP 0 LASTPIN (-6375 4875) $PN 174
J 0
(-6365 4885);
DISPLAY 0.680851 (-6365 4885);
PAINT MONO (-6365 4885);
FORCEPROP 0 LASTPIN (-6375 3225) $PN 267
J 0
(-6365 3235);
DISPLAY 0.680851 (-6365 3235);
PAINT MONO (-6365 3235);
FORCEPROP 0 LASTPIN (-6375 4925) $PN 176
J 0
(-6365 4935);
DISPLAY 0.680851 (-6365 4935);
PAINT MONO (-6365 4935);
FORCEPROP 0 LASTPIN (-6375 3275) $PN 269
J 0
(-6365 3285);
DISPLAY 0.680851 (-6365 3285);
PAINT MONO (-6365 3285);
FORCEPROP 0 LASTPIN (-6375 4975) $PN 36
J 0
(-6365 4985);
DISPLAY 0.680851 (-6365 4985);
PAINT MONO (-6365 4985);
FORCEPROP 0 LASTPIN (-6375 3325) $PN 129
J 0
(-6365 3335);
DISPLAY 0.680851 (-6365 3335);
PAINT MONO (-6365 3335);
FORCEPROP 0 LASTPIN (-6375 5025) $PN 38
J 0
(-6365 5035);
DISPLAY 0.680851 (-6365 5035);
PAINT MONO (-6365 5035);
FORCEPROP 0 LASTPIN (-6375 3375) $PN 131
J 0
(-6365 3385);
DISPLAY 0.680851 (-6365 3385);
PAINT MONO (-6365 3385);
FORCEPROP 0 LASTPIN (-6375 5075) $PN 181
J 0
(-6365 5085);
DISPLAY 0.680851 (-6365 5085);
PAINT MONO (-6365 5085);
FORCEPROP 0 LASTPIN (-6375 3425) $PN 274
J 0
(-6365 3435);
DISPLAY 0.680851 (-6365 3435);
PAINT MONO (-6365 3435);
FORCEPROP 0 LASTPIN (-6375 5125) $PN 183
J 0
(-6365 5135);
DISPLAY 0.680851 (-6365 5135);
PAINT MONO (-6365 5135);
FORCEPROP 0 LASTPIN (-6375 3475) $PN 276
J 0
(-6365 3485);
DISPLAY 0.680851 (-6365 3485);
PAINT MONO (-6365 3485);
FORCEPROP 0 LASTPIN (-6375 5175) $PN 40
J 0
(-6365 5185);
DISPLAY 0.680851 (-6365 5185);
PAINT MONO (-6365 5185);
FORCEPROP 0 LASTPIN (-6375 3525) $PN 133
J 0
(-6365 3535);
DISPLAY 0.680851 (-6365 3535);
PAINT MONO (-6365 3535);
FORCEPROP 0 LASTPIN (-6375 5225) $PN 42
J 0
(-6365 5235);
DISPLAY 0.680851 (-6365 5235);
PAINT MONO (-6365 5235);
FORCEPROP 0 LASTPIN (-6375 3575) $PN 135
J 0
(-6365 3585);
DISPLAY 0.680851 (-6365 3585);
PAINT MONO (-6365 3585);
FORCEPROP 0 LASTPIN (-6375 5275) $PN 185
J 0
(-6365 5285);
DISPLAY 0.680851 (-6365 5285);
PAINT MONO (-6365 5285);
FORCEPROP 0 LASTPIN (-6375 3625) $PN 278
J 0
(-6365 3635);
DISPLAY 0.680851 (-6365 3635);
PAINT MONO (-6365 3635);
FORCEPROP 0 LASTPIN (-6375 5325) $PN 187
J 0
(-6365 5335);
DISPLAY 0.680851 (-6365 5335);
PAINT MONO (-6365 5335);
FORCEPROP 0 LASTPIN (-6375 3675) $PN 280
J 0
(-6365 3685);
DISPLAY 0.680851 (-6365 3685);
PAINT MONO (-6365 3685);
FORCEPROP 0 LASTPIN (-6375 5375) $PN 47
J 0
(-6365 5385);
DISPLAY 0.680851 (-6365 5385);
PAINT MONO (-6365 5385);
FORCEPROP 0 LASTPIN (-6375 3725) $PN 140
J 0
(-6365 3735);
DISPLAY 0.680851 (-6365 3735);
PAINT MONO (-6365 3735);
FORCEPROP 0 LASTPIN (-6375 5425) $PN 49
J 0
(-6365 5435);
DISPLAY 0.680851 (-6365 5435);
PAINT MONO (-6365 5435);
FORCEPROP 0 LASTPIN (-6375 3775) $PN 142
J 0
(-6365 3785);
DISPLAY 0.680851 (-6365 3785);
PAINT MONO (-6365 3785);
FORCEPROP 0 LASTPIN (-6375 5475) $PN 192
J 0
(-6365 5485);
DISPLAY 0.680851 (-6365 5485);
PAINT MONO (-6365 5485);
FORCEPROP 0 LASTPIN (-6375 3825) $PN 285
J 0
(-6365 3835);
DISPLAY 0.680851 (-6365 3835);
PAINT MONO (-6365 3835);
FORCEPROP 0 LASTPIN (-6375 5525) $PN 194
J 0
(-6365 5535);
DISPLAY 0.680851 (-6365 5535);
PAINT MONO (-6365 5535);
FORCEPROP 0 LASTPIN (-6375 3875) $PN 287
J 0
(-6365 3885);
DISPLAY 0.680851 (-6365 3885);
PAINT MONO (-6365 3885);
FORCEPROP 0 LASTPIN (-7575 3025) $PN 148
J 2
(-7585 3035);
DISPLAY 0.680851 (-7585 3035);
PAINT MONO (-7585 3035);
FORCEPROP 0 LASTPIN (-7575 2925) $PN 4
J 2
(-7585 2935);
DISPLAY 0.680851 (-7585 2935);
PAINT MONO (-7585 2935);
FORCEPROP 0 LASTPIN (-7575 2975) $PN 5
J 2
(-7585 2985);
DISPLAY 0.680851 (-7585 2985);
PAINT MONO (-7585 2985);
FORCEPROP 0 LASTPIN (-7575 2125) $PN 86
J 2
(-7585 2135);
DISPLAY 0.680851 (-7585 2135);
PAINT MONO (-7585 2135);
FORCEPROP 0 LASTPIN (-7575 2075) $PN 87
J 2
(-7585 2085);
DISPLAY 0.680851 (-7585 2085);
PAINT MONO (-7585 2085);
FORCEPROP 0 LASTPIN (-7575 4725) $PN 74
J 2
(-7585 4735);
DISPLAY 0.680851 (-7585 4735);
PAINT MONO (-7585 4735);
FORCEPROP 0 LASTPIN (-7575 4675) $PN 227
J 2
(-7585 4685);
DISPLAY 0.680851 (-7585 4685);
PAINT MONO (-7585 4685);
FORCEPROP 0 LASTPIN (-7575 2675) $PN 147
J 2
(-7585 2685);
DISPLAY 0.680851 (-7585 2685);
PAINT MONO (-7585 2685);
FORCEPROP 0 LASTPIN (-7575 3225) $PN 207
J 2
(-7585 3235);
DISPLAY 0.680851 (-7585 3235);
PAINT MONO (-7585 3235);
FORCEPROP 0 LASTPIN (-7575 2275) $PN 2
J 2
(-7585 2285);
DISPLAY 0.680851 (-7585 2285);
PAINT MONO (-7585 2285);
FORCEPROP 0 LASTPIN (-7575 2325) $PN 144
J 2
(-7585 2335);
DISPLAY 0.680851 (-7585 2335);
PAINT MONO (-7585 2335);
FORCEPROP 0 LASTPIN (-7575 2375) $PN 149
J 2
(-7585 2385);
DISPLAY 0.680851 (-7585 2385);
PAINT MONO (-7585 2385);
FORCEPROP 0 LASTPIN (-7575 2425) $PN 150
J 2
(-7585 2435);
DISPLAY 0.680851 (-7585 2435);
PAINT MONO (-7585 2435);
FORCEPROP 0 LASTPIN (-7575 2475) $PN 220
J 2
(-7585 2485);
DISPLAY 0.680851 (-7585 2485);
PAINT MONO (-7585 2485);
FORCEPROP 0 LASTPIN (-7575 2525) $PN 231
J 2
(-7585 2535);
DISPLAY 0.680851 (-7585 2535);
PAINT MONO (-7585 2535);
FORCEPROP 0 LASTPIN (-7575 2575) $PN 232
J 2
(-7585 2585);
DISPLAY 0.680851 (-7585 2585);
PAINT MONO (-7585 2585);
FORCEPROP 0 LASTPIN (-7575 3075) $PN 3
J 2
(-7585 3085);
DISPLAY 0.680851 (-7585 3085);
PAINT MONO (-7585 3085);
FORCEPROP 2 LAST PART_TYPE SMLF
J 0
(-7425 5950);
DISPLAY 1.021277 (-7425 5950);
FORCEPROP 2 LAST VALUE SCONN288_DDR506112002KQ
J 0
(-7425 5900);
DISPLAY 0.489362 (-7425 5900);
PAINT SKYBLUE (-7425 5900);
FORCEPROP 1 LAST MATERIAL IO
J 0
(-7425 5700);
DISPLAY 0.468085 (-7425 5700);
PAINT SKYBLUE (-7425 5700);
FORCEPROP 1 LAST PART_NUMBER DFHST8FS479
J 0
(-7425 5775);
DISPLAY 0.468085 (-7425 5775);
PAINT SKYBLUE (-7425 5775);
FORCEPROP 1 LAST CDS_LMAN_SYM_OUTLINE -450,1900,450,-1850
J 0
(-6975 3775);
DISPLAY 0.468085 (-6975 3775);
PAINT GREEN (-6975 3775);
DISPLAY INVISIBLE (-6975 3775);
FORCEPROP 1 LAST PATH I22
J 0
(-6975 3775);
DISPLAY 0.723404 (-6975 3775);
PAINT GREEN (-6975 3775);
DISPLAY INVISIBLE (-6975 3775);
FORCEPROP 1 LAST NEEDS_NO_SIZE TRUE
J 0
(-6975 3775);
DISPLAY 0.723404 (-6975 3775);
PAINT GREEN (-6975 3775);
DISPLAY INVISIBLE (-6975 3775);
FORCEPROP 2 LAST CDS_LIB pure_quanta
J 0
(-6975 3775);
DISPLAY INVISIBLE (-6975 3775);
FORCEADD TAP..1
(-3500 3550);
FORCEPROP 3 LASTPIN (-3550 3550) SIG_NAME M_F_CPU1_SB_DQS_DP<8>
J 0
(-3540 3560);
DISPLAY 0.659574 (-3540 3560);
PAINT MONO (-3540 3560);
DISPLAY INVISIBLE (-3540 3560);
FORCEPROP 1 LASTPIN (-3550 3550) BN 8
J 0
(-3562 3558);
DISPLAY 0.489362 (-3562 3558);
PAINT GREEN (-3562 3558);
FORCEPROP 2 LAST CDS_LIB mstr_standard
J 0
(-3500 3550);
DISPLAY 0.723404 (-3500 3550);
PAINT MONO (-3500 3550);
DISPLAY INVISIBLE (-3500 3550);
FORCEPROP 1 LAST BODY_TYPE PLUMBING
J 0
(-3500 3600);
DISPLAY 0.872340 (-3500 3600);
PAINT GREEN (-3500 3600);
DISPLAY INVISIBLE (-3500 3600);
FORCEPROP 1 LAST HDL_TAP TRUE
J 0
(-3175 3425);
DISPLAY 0.872340 (-3175 3425);
DISPLAY INVISIBLE (-3175 3425);
FORCEPROP 1 LAST PATH I220
J 0
(-3502 3550);
DISPLAY 0.872340 (-3502 3550);
PAINT GREEN (-3502 3550);
DISPLAY INVISIBLE (-3502 3550);
FORCEADD TAP..1
(-3500 3450);
FORCEPROP 3 LASTPIN (-3550 3450) SIG_NAME M_F_CPU1_SB_DQS_DP<7>
J 0
(-3540 3460);
DISPLAY 0.659574 (-3540 3460);
PAINT MONO (-3540 3460);
DISPLAY INVISIBLE (-3540 3460);
FORCEPROP 1 LASTPIN (-3550 3450) BN 7
J 0
(-3562 3458);
DISPLAY 0.489362 (-3562 3458);
PAINT GREEN (-3562 3458);
FORCEPROP 2 LAST CDS_LIB mstr_standard
J 0
(-3500 3450);
DISPLAY 0.723404 (-3500 3450);
PAINT MONO (-3500 3450);
DISPLAY INVISIBLE (-3500 3450);
FORCEPROP 1 LAST BODY_TYPE PLUMBING
J 0
(-3500 3500);
DISPLAY 0.872340 (-3500 3500);
PAINT GREEN (-3500 3500);
DISPLAY INVISIBLE (-3500 3500);
FORCEPROP 1 LAST HDL_TAP TRUE
J 0
(-3175 3325);
DISPLAY 0.872340 (-3175 3325);
DISPLAY INVISIBLE (-3175 3325);
FORCEPROP 1 LAST PATH I221
J 0
(-3502 3450);
DISPLAY 0.872340 (-3502 3450);
PAINT GREEN (-3502 3450);
DISPLAY INVISIBLE (-3502 3450);
FORCEADD TAP..1
(-3300 3300);
FORCEPROP 3 LASTPIN (-3350 3300) SIG_NAME M_F_CPU1_SB_DQS_DN<6>
J 0
(-3340 3310);
DISPLAY 0.659574 (-3340 3310);
PAINT MONO (-3340 3310);
DISPLAY INVISIBLE (-3340 3310);
FORCEPROP 1 LASTPIN (-3350 3300) BN 6
J 0
(-3362 3308);
DISPLAY 0.489362 (-3362 3308);
PAINT GREEN (-3362 3308);
FORCEPROP 2 LAST CDS_LIB mstr_standard
J 0
(-3300 3300);
DISPLAY 0.723404 (-3300 3300);
PAINT MONO (-3300 3300);
DISPLAY INVISIBLE (-3300 3300);
FORCEPROP 1 LAST BODY_TYPE PLUMBING
J 0
(-3300 3350);
DISPLAY 0.872340 (-3300 3350);
PAINT GREEN (-3300 3350);
DISPLAY INVISIBLE (-3300 3350);
FORCEPROP 1 LAST HDL_TAP TRUE
J 0
(-2975 3175);
DISPLAY 0.872340 (-2975 3175);
DISPLAY INVISIBLE (-2975 3175);
FORCEPROP 1 LAST PATH I222
J 0
(-3302 3300);
DISPLAY 0.872340 (-3302 3300);
PAINT GREEN (-3302 3300);
DISPLAY INVISIBLE (-3302 3300);
FORCEADD TAP..1
(-3300 3200);
FORCEPROP 3 LASTPIN (-3350 3200) SIG_NAME M_F_CPU1_SB_DQS_DN<5>
J 0
(-3340 3210);
DISPLAY 0.659574 (-3340 3210);
PAINT MONO (-3340 3210);
DISPLAY INVISIBLE (-3340 3210);
FORCEPROP 1 LASTPIN (-3350 3200) BN 5
J 0
(-3362 3208);
DISPLAY 0.489362 (-3362 3208);
PAINT GREEN (-3362 3208);
FORCEPROP 2 LAST CDS_LIB mstr_standard
J 0
(-3300 3200);
DISPLAY 0.723404 (-3300 3200);
PAINT MONO (-3300 3200);
DISPLAY INVISIBLE (-3300 3200);
FORCEPROP 1 LAST BODY_TYPE PLUMBING
J 0
(-3300 3250);
DISPLAY 0.872340 (-3300 3250);
PAINT GREEN (-3300 3250);
DISPLAY INVISIBLE (-3300 3250);
FORCEPROP 1 LAST HDL_TAP TRUE
J 0
(-2975 3075);
DISPLAY 0.872340 (-2975 3075);
DISPLAY INVISIBLE (-2975 3075);
FORCEPROP 1 LAST PATH I223
J 0
(-3302 3200);
DISPLAY 0.872340 (-3302 3200);
PAINT GREEN (-3302 3200);
DISPLAY INVISIBLE (-3302 3200);
FORCEADD TAP..1
(-3300 3000);
FORCEPROP 3 LASTPIN (-3350 3000) SIG_NAME M_F_CPU1_SB_DQS_DN<3>
J 0
(-3340 3010);
DISPLAY 0.659574 (-3340 3010);
PAINT MONO (-3340 3010);
DISPLAY INVISIBLE (-3340 3010);
FORCEPROP 1 LASTPIN (-3350 3000) BN 3
J 0
(-3362 3008);
DISPLAY 0.489362 (-3362 3008);
PAINT GREEN (-3362 3008);
FORCEPROP 2 LAST CDS_LIB mstr_standard
J 0
(-3300 3000);
DISPLAY 0.723404 (-3300 3000);
PAINT MONO (-3300 3000);
DISPLAY INVISIBLE (-3300 3000);
FORCEPROP 1 LAST BODY_TYPE PLUMBING
J 0
(-3300 3050);
DISPLAY 0.872340 (-3300 3050);
PAINT GREEN (-3300 3050);
DISPLAY INVISIBLE (-3300 3050);
FORCEPROP 1 LAST HDL_TAP TRUE
J 0
(-2975 2875);
DISPLAY 0.872340 (-2975 2875);
DISPLAY INVISIBLE (-2975 2875);
FORCEPROP 1 LAST PATH I224
J 0
(-3302 3000);
DISPLAY 0.872340 (-3302 3000);
PAINT GREEN (-3302 3000);
DISPLAY INVISIBLE (-3302 3000);
FORCEADD TAP..1
(-3300 3100);
FORCEPROP 3 LASTPIN (-3350 3100) SIG_NAME M_F_CPU1_SB_DQS_DN<4>
J 0
(-3340 3110);
DISPLAY 0.659574 (-3340 3110);
PAINT MONO (-3340 3110);
DISPLAY INVISIBLE (-3340 3110);
FORCEPROP 1 LASTPIN (-3350 3100) BN 4
J 0
(-3362 3108);
DISPLAY 0.489362 (-3362 3108);
PAINT GREEN (-3362 3108);
FORCEPROP 2 LAST CDS_LIB mstr_standard
J 0
(-3300 3100);
DISPLAY 0.723404 (-3300 3100);
PAINT MONO (-3300 3100);
DISPLAY INVISIBLE (-3300 3100);
FORCEPROP 1 LAST BODY_TYPE PLUMBING
J 0
(-3300 3150);
DISPLAY 0.872340 (-3300 3150);
PAINT GREEN (-3300 3150);
DISPLAY INVISIBLE (-3300 3150);
FORCEPROP 1 LAST HDL_TAP TRUE
J 0
(-2975 2975);
DISPLAY 0.872340 (-2975 2975);
DISPLAY INVISIBLE (-2975 2975);
FORCEPROP 1 LAST PATH I225
J 0
(-3302 3100);
DISPLAY 0.872340 (-3302 3100);
PAINT GREEN (-3302 3100);
DISPLAY INVISIBLE (-3302 3100);
FORCEADD TAP..1
(-3300 2900);
FORCEPROP 3 LASTPIN (-3350 2900) SIG_NAME M_F_CPU1_SB_DQS_DN<2>
J 0
(-3340 2910);
DISPLAY 0.659574 (-3340 2910);
PAINT MONO (-3340 2910);
DISPLAY INVISIBLE (-3340 2910);
FORCEPROP 1 LASTPIN (-3350 2900) BN 2
J 0
(-3362 2908);
DISPLAY 0.489362 (-3362 2908);
PAINT GREEN (-3362 2908);
FORCEPROP 2 LAST CDS_LIB mstr_standard
J 0
(-3300 2900);
DISPLAY 0.723404 (-3300 2900);
PAINT MONO (-3300 2900);
DISPLAY INVISIBLE (-3300 2900);
FORCEPROP 1 LAST BODY_TYPE PLUMBING
J 0
(-3300 2950);
DISPLAY 0.872340 (-3300 2950);
PAINT GREEN (-3300 2950);
DISPLAY INVISIBLE (-3300 2950);
FORCEPROP 1 LAST HDL_TAP TRUE
J 0
(-2975 2775);
DISPLAY 0.872340 (-2975 2775);
DISPLAY INVISIBLE (-2975 2775);
FORCEPROP 1 LAST PATH I226
J 0
(-3302 2900);
DISPLAY 0.872340 (-3302 2900);
PAINT GREEN (-3302 2900);
DISPLAY INVISIBLE (-3302 2900);
FORCEADD TAP..1
(-3500 3150);
FORCEPROP 3 LASTPIN (-3550 3150) SIG_NAME M_F_CPU1_SB_DQS_DP<4>
J 0
(-3540 3160);
DISPLAY 0.659574 (-3540 3160);
PAINT MONO (-3540 3160);
DISPLAY INVISIBLE (-3540 3160);
FORCEPROP 1 LASTPIN (-3550 3150) BN 4
J 0
(-3562 3158);
DISPLAY 0.489362 (-3562 3158);
PAINT GREEN (-3562 3158);
FORCEPROP 2 LAST CDS_LIB mstr_standard
J 0
(-3500 3150);
DISPLAY 0.723404 (-3500 3150);
PAINT MONO (-3500 3150);
DISPLAY INVISIBLE (-3500 3150);
FORCEPROP 1 LAST BODY_TYPE PLUMBING
J 0
(-3500 3200);
DISPLAY 0.872340 (-3500 3200);
PAINT GREEN (-3500 3200);
DISPLAY INVISIBLE (-3500 3200);
FORCEPROP 1 LAST HDL_TAP TRUE
J 0
(-3175 3025);
DISPLAY 0.872340 (-3175 3025);
DISPLAY INVISIBLE (-3175 3025);
FORCEPROP 1 LAST PATH I227
J 0
(-3502 3150);
DISPLAY 0.872340 (-3502 3150);
PAINT GREEN (-3502 3150);
DISPLAY INVISIBLE (-3502 3150);
FORCEADD TAP..1
(-3500 3350);
FORCEPROP 3 LASTPIN (-3550 3350) SIG_NAME M_F_CPU1_SB_DQS_DP<6>
J 0
(-3540 3360);
DISPLAY 0.659574 (-3540 3360);
PAINT MONO (-3540 3360);
DISPLAY INVISIBLE (-3540 3360);
FORCEPROP 1 LASTPIN (-3550 3350) BN 6
J 0
(-3562 3358);
DISPLAY 0.489362 (-3562 3358);
PAINT GREEN (-3562 3358);
FORCEPROP 2 LAST CDS_LIB mstr_standard
J 0
(-3500 3350);
DISPLAY 0.723404 (-3500 3350);
PAINT MONO (-3500 3350);
DISPLAY INVISIBLE (-3500 3350);
FORCEPROP 1 LAST BODY_TYPE PLUMBING
J 0
(-3500 3400);
DISPLAY 0.872340 (-3500 3400);
PAINT GREEN (-3500 3400);
DISPLAY INVISIBLE (-3500 3400);
FORCEPROP 1 LAST HDL_TAP TRUE
J 0
(-3175 3225);
DISPLAY 0.872340 (-3175 3225);
DISPLAY INVISIBLE (-3175 3225);
FORCEPROP 1 LAST PATH I228
J 0
(-3502 3350);
DISPLAY 0.872340 (-3502 3350);
PAINT GREEN (-3502 3350);
DISPLAY INVISIBLE (-3502 3350);
FORCEADD TAP..1
(-3500 3250);
FORCEPROP 3 LASTPIN (-3550 3250) SIG_NAME M_F_CPU1_SB_DQS_DP<5>
J 0
(-3540 3260);
DISPLAY 0.659574 (-3540 3260);
PAINT MONO (-3540 3260);
DISPLAY INVISIBLE (-3540 3260);
FORCEPROP 1 LASTPIN (-3550 3250) BN 5
J 0
(-3562 3258);
DISPLAY 0.489362 (-3562 3258);
PAINT GREEN (-3562 3258);
FORCEPROP 2 LAST CDS_LIB mstr_standard
J 0
(-3500 3250);
DISPLAY 0.723404 (-3500 3250);
PAINT MONO (-3500 3250);
DISPLAY INVISIBLE (-3500 3250);
FORCEPROP 1 LAST BODY_TYPE PLUMBING
J 0
(-3500 3300);
DISPLAY 0.872340 (-3500 3300);
PAINT GREEN (-3500 3300);
DISPLAY INVISIBLE (-3500 3300);
FORCEPROP 1 LAST HDL_TAP TRUE
J 0
(-3175 3125);
DISPLAY 0.872340 (-3175 3125);
DISPLAY INVISIBLE (-3175 3125);
FORCEPROP 1 LAST PATH I229
J 0
(-3502 3250);
DISPLAY 0.872340 (-3502 3250);
PAINT GREEN (-3502 3250);
DISPLAY INVISIBLE (-3502 3250);
FORCEADD TAP..1
R 2
(-7825 3325);
FORCEPROP 3 LASTPIN (-7775 3325) SIG_NAME M_F_CPU1_SB_CB<0>
J 0
(-7765 3335);
DISPLAY 0.659574 (-7765 3335);
PAINT MONO (-7765 3335);
DISPLAY INVISIBLE (-7765 3335);
FORCEPROP 1 LASTPIN (-7775 3325) BN 0
J 2
(-7763 3333);
DISPLAY 0.489362 (-7763 3333);
PAINT GREEN (-7763 3333);
FORCEPROP 2 LAST CDS_LIB mstr_standard
J 0
(-7825 3325);
DISPLAY 0.723404 (-7825 3325);
PAINT MONO (-7825 3325);
DISPLAY INVISIBLE (-7825 3325);
FORCEPROP 1 LAST BODY_TYPE PLUMBING
J 2
(-7825 3375);
DISPLAY 0.872340 (-7825 3375);
PAINT GREEN (-7825 3375);
DISPLAY INVISIBLE (-7825 3375);
FORCEPROP 1 LAST HDL_TAP TRUE
J 2
(-8150 3200);
DISPLAY 0.872340 (-8150 3200);
DISPLAY INVISIBLE (-8150 3200);
FORCEPROP 1 LAST PATH I23
J 2
(-7823 3325);
DISPLAY 0.872340 (-7823 3325);
PAINT GREEN (-7823 3325);
DISPLAY INVISIBLE (-7823 3325);
FORCEADD TAP..1
(-3500 2950);
FORCEPROP 3 LASTPIN (-3550 2950) SIG_NAME M_F_CPU1_SB_DQS_DP<2>
J 0
(-3540 2960);
DISPLAY 0.659574 (-3540 2960);
PAINT MONO (-3540 2960);
DISPLAY INVISIBLE (-3540 2960);
FORCEPROP 1 LASTPIN (-3550 2950) BN 2
J 0
(-3562 2958);
DISPLAY 0.489362 (-3562 2958);
PAINT GREEN (-3562 2958);
FORCEPROP 2 LAST CDS_LIB mstr_standard
J 0
(-3500 2950);
DISPLAY 0.723404 (-3500 2950);
PAINT MONO (-3500 2950);
DISPLAY INVISIBLE (-3500 2950);
FORCEPROP 1 LAST BODY_TYPE PLUMBING
J 0
(-3500 3000);
DISPLAY 0.872340 (-3500 3000);
PAINT GREEN (-3500 3000);
DISPLAY INVISIBLE (-3500 3000);
FORCEPROP 1 LAST HDL_TAP TRUE
J 0
(-3175 2825);
DISPLAY 0.872340 (-3175 2825);
DISPLAY INVISIBLE (-3175 2825);
FORCEPROP 1 LAST PATH I230
J 0
(-3502 2950);
DISPLAY 0.872340 (-3502 2950);
PAINT GREEN (-3502 2950);
DISPLAY INVISIBLE (-3502 2950);
FORCEADD TAP..1
(-3500 3050);
FORCEPROP 3 LASTPIN (-3550 3050) SIG_NAME M_F_CPU1_SB_DQS_DP<3>
J 0
(-3540 3060);
DISPLAY 0.659574 (-3540 3060);
PAINT MONO (-3540 3060);
DISPLAY INVISIBLE (-3540 3060);
FORCEPROP 1 LASTPIN (-3550 3050) BN 3
J 0
(-3562 3058);
DISPLAY 0.489362 (-3562 3058);
PAINT GREEN (-3562 3058);
FORCEPROP 2 LAST CDS_LIB mstr_standard
J 0
(-3500 3050);
DISPLAY 0.723404 (-3500 3050);
PAINT MONO (-3500 3050);
DISPLAY INVISIBLE (-3500 3050);
FORCEPROP 1 LAST BODY_TYPE PLUMBING
J 0
(-3500 3100);
DISPLAY 0.872340 (-3500 3100);
PAINT GREEN (-3500 3100);
DISPLAY INVISIBLE (-3500 3100);
FORCEPROP 1 LAST HDL_TAP TRUE
J 0
(-3175 2925);
DISPLAY 0.872340 (-3175 2925);
DISPLAY INVISIBLE (-3175 2925);
FORCEPROP 1 LAST PATH I231
J 0
(-3502 3050);
DISPLAY 0.872340 (-3502 3050);
PAINT GREEN (-3502 3050);
DISPLAY INVISIBLE (-3502 3050);
FORCEADD TAP..1
(-3300 2800);
FORCEPROP 3 LASTPIN (-3350 2800) SIG_NAME M_F_CPU1_SB_DQS_DN<1>
J 0
(-3340 2810);
DISPLAY 0.659574 (-3340 2810);
PAINT MONO (-3340 2810);
DISPLAY INVISIBLE (-3340 2810);
FORCEPROP 1 LASTPIN (-3350 2800) BN 1
J 0
(-3362 2808);
DISPLAY 0.489362 (-3362 2808);
PAINT GREEN (-3362 2808);
FORCEPROP 2 LAST CDS_LIB mstr_standard
J 0
(-3300 2800);
DISPLAY 0.723404 (-3300 2800);
PAINT MONO (-3300 2800);
DISPLAY INVISIBLE (-3300 2800);
FORCEPROP 1 LAST BODY_TYPE PLUMBING
J 0
(-3300 2850);
DISPLAY 0.872340 (-3300 2850);
PAINT GREEN (-3300 2850);
DISPLAY INVISIBLE (-3300 2850);
FORCEPROP 1 LAST HDL_TAP TRUE
J 0
(-2975 2675);
DISPLAY 0.872340 (-2975 2675);
DISPLAY INVISIBLE (-2975 2675);
FORCEPROP 1 LAST PATH I232
J 0
(-3302 2800);
DISPLAY 0.872340 (-3302 2800);
PAINT GREEN (-3302 2800);
DISPLAY INVISIBLE (-3302 2800);
FORCEADD TAP..1
(-3300 2700);
FORCEPROP 3 LASTPIN (-3350 2700) SIG_NAME M_F_CPU1_SB_DQS_DN<0>
J 0
(-3340 2710);
DISPLAY 0.659574 (-3340 2710);
PAINT MONO (-3340 2710);
DISPLAY INVISIBLE (-3340 2710);
FORCEPROP 1 LASTPIN (-3350 2700) BN 0
J 0
(-3362 2708);
DISPLAY 0.489362 (-3362 2708);
PAINT GREEN (-3362 2708);
FORCEPROP 2 LAST CDS_LIB mstr_standard
J 0
(-3300 2700);
DISPLAY 0.723404 (-3300 2700);
PAINT MONO (-3300 2700);
DISPLAY INVISIBLE (-3300 2700);
FORCEPROP 1 LAST BODY_TYPE PLUMBING
J 0
(-3300 2750);
DISPLAY 0.872340 (-3300 2750);
PAINT GREEN (-3300 2750);
DISPLAY INVISIBLE (-3300 2750);
FORCEPROP 1 LAST HDL_TAP TRUE
J 0
(-2975 2575);
DISPLAY 0.872340 (-2975 2575);
DISPLAY INVISIBLE (-2975 2575);
FORCEPROP 1 LAST PATH I233
J 0
(-3302 2700);
DISPLAY 0.872340 (-3302 2700);
PAINT GREEN (-3302 2700);
DISPLAY INVISIBLE (-3302 2700);
FORCEADD TAP..1
(-3500 2750);
FORCEPROP 3 LASTPIN (-3550 2750) SIG_NAME M_F_CPU1_SB_DQS_DP<0>
J 0
(-3540 2760);
DISPLAY 0.659574 (-3540 2760);
PAINT MONO (-3540 2760);
DISPLAY INVISIBLE (-3540 2760);
FORCEPROP 1 LASTPIN (-3550 2750) BN 0
J 0
(-3562 2758);
DISPLAY 0.489362 (-3562 2758);
PAINT GREEN (-3562 2758);
FORCEPROP 2 LAST CDS_LIB mstr_standard
J 0
(-3500 2750);
DISPLAY 0.723404 (-3500 2750);
PAINT MONO (-3500 2750);
DISPLAY INVISIBLE (-3500 2750);
FORCEPROP 1 LAST BODY_TYPE PLUMBING
J 0
(-3500 2800);
DISPLAY 0.872340 (-3500 2800);
PAINT GREEN (-3500 2800);
DISPLAY INVISIBLE (-3500 2800);
FORCEPROP 1 LAST HDL_TAP TRUE
J 0
(-3175 2625);
DISPLAY 0.872340 (-3175 2625);
DISPLAY INVISIBLE (-3175 2625);
FORCEPROP 1 LAST PATH I234
J 0
(-3502 2750);
DISPLAY 0.872340 (-3502 2750);
PAINT GREEN (-3502 2750);
DISPLAY INVISIBLE (-3502 2750);
FORCEADD TAP..1
(-3500 2850);
FORCEPROP 3 LASTPIN (-3550 2850) SIG_NAME M_F_CPU1_SB_DQS_DP<1>
J 0
(-3540 2860);
DISPLAY 0.659574 (-3540 2860);
PAINT MONO (-3540 2860);
DISPLAY INVISIBLE (-3540 2860);
FORCEPROP 1 LASTPIN (-3550 2850) BN 1
J 0
(-3562 2858);
DISPLAY 0.489362 (-3562 2858);
PAINT GREEN (-3562 2858);
FORCEPROP 2 LAST CDS_LIB mstr_standard
J 0
(-3500 2850);
DISPLAY 0.723404 (-3500 2850);
PAINT MONO (-3500 2850);
DISPLAY INVISIBLE (-3500 2850);
FORCEPROP 1 LAST BODY_TYPE PLUMBING
J 0
(-3500 2900);
DISPLAY 0.872340 (-3500 2900);
PAINT GREEN (-3500 2900);
DISPLAY INVISIBLE (-3500 2900);
FORCEPROP 1 LAST HDL_TAP TRUE
J 0
(-3175 2725);
DISPLAY 0.872340 (-3175 2725);
DISPLAY INVISIBLE (-3175 2725);
FORCEPROP 1 LAST PATH I235
J 0
(-3502 2850);
DISPLAY 0.872340 (-3502 2850);
PAINT GREEN (-3502 2850);
DISPLAY INVISIBLE (-3502 2850);
FORCEADD SCONN288_DDR506112002KQ..2
(-4450 3700);
FORCEPROP 1 LAST LOCATION J33
J 0
(-5050 5025);
DISPLAY 0.468085 (-5050 5025);
PAINT SKYBLUE (-5050 5025);
FORCEPROP 0 LAST $SEC 2
J 0
(-4900 5175);
DISPLAY 0.680851 (-4900 5175);
PAINT MONO (-4900 5175);
DISPLAY INVISIBLE (-4900 5175);
FORCEPROP 0 LAST CDS_SEC 2
J 0
(-4900 5175);
DISPLAY 1.021277 (-4900 5175);
DISPLAY INVISIBLE (-4900 5175);
FORCEPROP 0 LASTPIN (-3700 3750) $PN 12
J 0
(-3690 3760);
DISPLAY 0.680851 (-3690 3760);
PAINT MONO (-3690 3760);
FORCEPROP 0 LASTPIN (-3700 3800) $PN 11
J 0
(-3690 3810);
DISPLAY 0.680851 (-3690 3810);
PAINT MONO (-3690 3810);
FORCEPROP 0 LASTPIN (-3700 2700) $PN 105
J 0
(-3690 2710);
DISPLAY 0.680851 (-3690 2710);
PAINT MONO (-3690 2710);
FORCEPROP 0 LASTPIN (-3700 2750) $PN 104
J 0
(-3690 2760);
DISPLAY 0.680851 (-3690 2760);
PAINT MONO (-3690 2760);
FORCEPROP 0 LASTPIN (-3700 3850) $PN 23
J 0
(-3690 3860);
DISPLAY 0.680851 (-3690 3860);
PAINT MONO (-3690 3860);
FORCEPROP 0 LASTPIN (-3700 3900) $PN 22
J 0
(-3690 3910);
DISPLAY 0.680851 (-3690 3910);
PAINT MONO (-3690 3910);
FORCEPROP 0 LASTPIN (-3700 2800) $PN 116
J 0
(-3690 2810);
DISPLAY 0.680851 (-3690 2810);
PAINT MONO (-3690 2810);
FORCEPROP 0 LASTPIN (-3700 2850) $PN 115
J 0
(-3690 2860);
DISPLAY 0.680851 (-3690 2860);
PAINT MONO (-3690 2860);
FORCEPROP 0 LASTPIN (-3700 3950) $PN 34
J 0
(-3690 3960);
DISPLAY 0.680851 (-3690 3960);
PAINT MONO (-3690 3960);
FORCEPROP 0 LASTPIN (-3700 4000) $PN 33
J 0
(-3690 4010);
DISPLAY 0.680851 (-3690 4010);
PAINT MONO (-3690 4010);
FORCEPROP 0 LASTPIN (-3700 2900) $PN 127
J 0
(-3690 2910);
DISPLAY 0.680851 (-3690 2910);
PAINT MONO (-3690 2910);
FORCEPROP 0 LASTPIN (-3700 2950) $PN 126
J 0
(-3690 2960);
DISPLAY 0.680851 (-3690 2960);
PAINT MONO (-3690 2960);
FORCEPROP 0 LASTPIN (-3700 4050) $PN 45
J 0
(-3690 4060);
DISPLAY 0.680851 (-3690 4060);
PAINT MONO (-3690 4060);
FORCEPROP 0 LASTPIN (-3700 4100) $PN 44
J 0
(-3690 4110);
DISPLAY 0.680851 (-3690 4110);
PAINT MONO (-3690 4110);
FORCEPROP 0 LASTPIN (-3700 3000) $PN 138
J 0
(-3690 3010);
DISPLAY 0.680851 (-3690 3010);
PAINT MONO (-3690 3010);
FORCEPROP 0 LASTPIN (-3700 3050) $PN 137
J 0
(-3690 3060);
DISPLAY 0.680851 (-3690 3060);
PAINT MONO (-3690 3060);
FORCEPROP 0 LASTPIN (-3700 4150) $PN 56
J 0
(-3690 4160);
DISPLAY 0.680851 (-3690 4160);
PAINT MONO (-3690 4160);
FORCEPROP 0 LASTPIN (-3700 4200) $PN 55
J 0
(-3690 4210);
DISPLAY 0.680851 (-3690 4210);
PAINT MONO (-3690 4210);
FORCEPROP 0 LASTPIN (-3700 3100) $PN 238
J 0
(-3690 3110);
DISPLAY 0.680851 (-3690 3110);
PAINT MONO (-3690 3110);
FORCEPROP 0 LASTPIN (-3700 3150) $PN 239
J 0
(-3690 3160);
DISPLAY 0.680851 (-3690 3160);
PAINT MONO (-3690 3160);
FORCEPROP 0 LASTPIN (-3700 4250) $PN 156
J 0
(-3690 4260);
DISPLAY 0.680851 (-3690 4260);
PAINT MONO (-3690 4260);
FORCEPROP 0 LASTPIN (-3700 4300) $PN 157
J 0
(-3690 4310);
DISPLAY 0.680851 (-3690 4310);
PAINT MONO (-3690 4310);
FORCEPROP 0 LASTPIN (-3700 3200) $PN 249
J 0
(-3690 3210);
DISPLAY 0.680851 (-3690 3210);
PAINT MONO (-3690 3210);
FORCEPROP 0 LASTPIN (-3700 3250) $PN 250
J 0
(-3690 3260);
DISPLAY 0.680851 (-3690 3260);
PAINT MONO (-3690 3260);
FORCEPROP 0 LASTPIN (-3700 4350) $PN 167
J 0
(-3690 4360);
DISPLAY 0.680851 (-3690 4360);
PAINT MONO (-3690 4360);
FORCEPROP 0 LASTPIN (-3700 4400) $PN 168
J 0
(-3690 4410);
DISPLAY 0.680851 (-3690 4410);
PAINT MONO (-3690 4410);
FORCEPROP 0 LASTPIN (-3700 3300) $PN 260
J 0
(-3690 3310);
DISPLAY 0.680851 (-3690 3310);
PAINT MONO (-3690 3310);
FORCEPROP 0 LASTPIN (-3700 3350) $PN 261
J 0
(-3690 3360);
DISPLAY 0.680851 (-3690 3360);
PAINT MONO (-3690 3360);
FORCEPROP 0 LASTPIN (-3700 4450) $PN 178
J 0
(-3690 4460);
DISPLAY 0.680851 (-3690 4460);
PAINT MONO (-3690 4460);
FORCEPROP 0 LASTPIN (-3700 4500) $PN 179
J 0
(-3690 4510);
DISPLAY 0.680851 (-3690 4510);
PAINT MONO (-3690 4510);
FORCEPROP 0 LASTPIN (-3700 3400) $PN 271
J 0
(-3690 3410);
DISPLAY 0.680851 (-3690 3410);
PAINT MONO (-3690 3410);
FORCEPROP 0 LASTPIN (-3700 3450) $PN 272
J 0
(-3690 3460);
DISPLAY 0.680851 (-3690 3460);
PAINT MONO (-3690 3460);
FORCEPROP 0 LASTPIN (-3700 4550) $PN 189
J 0
(-3690 4560);
DISPLAY 0.680851 (-3690 4560);
PAINT MONO (-3690 4560);
FORCEPROP 0 LASTPIN (-3700 4600) $PN 190
J 0
(-3690 4610);
DISPLAY 0.680851 (-3690 4610);
PAINT MONO (-3690 4610);
FORCEPROP 0 LASTPIN (-3700 3500) $PN 282
J 0
(-3690 3510);
DISPLAY 0.680851 (-3690 3510);
PAINT MONO (-3690 3510);
FORCEPROP 0 LASTPIN (-3700 3550) $PN 283
J 0
(-3690 3560);
DISPLAY 0.680851 (-3690 3560);
PAINT MONO (-3690 3560);
FORCEPROP 0 LASTPIN (-3700 4650) $PN 200
J 0
(-3690 4660);
DISPLAY 0.680851 (-3690 4660);
PAINT MONO (-3690 4660);
FORCEPROP 0 LASTPIN (-3700 4700) $PN 201
J 0
(-3690 4710);
DISPLAY 0.680851 (-3690 4710);
PAINT MONO (-3690 4710);
FORCEPROP 0 LASTPIN (-3700 3600) $PN 94
J 0
(-3690 3610);
DISPLAY 0.680851 (-3690 3610);
PAINT MONO (-3690 3610);
FORCEPROP 0 LASTPIN (-3700 3650) $PN 93
J 0
(-3690 3660);
DISPLAY 0.680851 (-3690 3660);
PAINT MONO (-3690 3660);
FORCEPROP 2 LAST VALUE SCONN288_DDR506112002KQ
J 0
(-4900 5075);
DISPLAY 0.489362 (-4900 5075);
PAINT SKYBLUE (-4900 5075);
FORCEPROP 1 LAST MATERIAL IO
J 0
(-5050 4875);
DISPLAY 0.468085 (-5050 4875);
PAINT SKYBLUE (-5050 4875);
FORCEPROP 2 LAST PART_TYPE SMLF
J 0
(-4900 5125);
DISPLAY 1.021277 (-4900 5125);
FORCEPROP 1 LAST PART_NUMBER DFHST8FS479
J 0
(-5050 4950);
DISPLAY 0.468085 (-5050 4950);
PAINT SKYBLUE (-5050 4950);
FORCEPROP 1 LAST CDS_LMAN_SYM_OUTLINE -600,1150,600,-1150
J 0
(-4450 3700);
DISPLAY 0.468085 (-4450 3700);
PAINT GREEN (-4450 3700);
DISPLAY INVISIBLE (-4450 3700);
FORCEPROP 1 LAST PATH I236
J 0
(-4450 3700);
DISPLAY 0.723404 (-4450 3700);
PAINT GREEN (-4450 3700);
DISPLAY INVISIBLE (-4450 3700);
FORCEPROP 1 LAST NEEDS_NO_SIZE TRUE
J 0
(-4450 3700);
DISPLAY 0.723404 (-4450 3700);
PAINT GREEN (-4450 3700);
DISPLAY INVISIBLE (-4450 3700);
FORCEPROP 2 LAST CDS_LIB pure_quanta
J 0
(-4450 3700);
DISPLAY INVISIBLE (-4450 3700);
FORCEADD GND..1
(-2900 5650);
FORCEPROP 3 LASTPIN (-2900 5700) SIG_NAME GND\g
J 0
(-2890 5710);
DISPLAY 0.659574 (-2890 5710);
PAINT MONO (-2890 5710);
DISPLAY INVISIBLE (-2890 5710);
FORCEPROP 2 LAST CDS_LIB pure_quanta_power
J 0
(-2900 5650);
DISPLAY INVISIBLE (-2900 5650);
FORCEPROP 2 LAST BOM_COST MEM
J 0
(-2875 5775);
DISPLAY 0.659574 (-2875 5775);
DISPLAY INVISIBLE (-2875 5775);
FORCEPROP 1 LAST SIZE 1B
J 0
(-2825 5600);
DISPLAY 0.723404 (-2825 5600);
PAINT GREEN (-2825 5600);
DISPLAY INVISIBLE (-2825 5600);
FORCEPROP 1 LAST PATH I237
J 0
(-2825 5650);
DISPLAY 0.872340 (-2825 5650);
PAINT AQUA (-2825 5650);
DISPLAY INVISIBLE (-2825 5650);
FORCEPROP 2 LAST ROOM MEM_EFGH_DECOUPLING_CAPS
J 0
(-2875 5725);
DISPLAY 0.659574 (-2875 5725);
PAINT RED (-2875 5725);
DISPLAY INVISIBLE (-2875 5725);
FORCEPROP 1 LAST HDL_POWER GND
J 0
(-2900 5800);
DISPLAY 0.723404 (-2900 5800);
PAINT GREEN (-2900 5800);
DISPLAY INVISIBLE (-2900 5800);
FORCEADD Q_CAP..1
R 2
(-2900 6000);
FORCEPROP 1 LAST LOCATION C518
J 2
(-2950 6100);
DISPLAY 0.489362 (-2950 6100);
PAINT SKYBLUE (-2950 6100);
FORCEPROP 0 LAST $SEC 1
J 0
(-2950 6150);
DISPLAY 0.680851 (-2950 6150);
PAINT MONO (-2950 6150);
DISPLAY INVISIBLE (-2950 6150);
FORCEPROP 0 LAST CDS_SEC 1
J 0
(-2950 6150);
DISPLAY 0.680851 (-2950 6150);
DISPLAY INVISIBLE (-2950 6150);
FORCEPROP 1 LASTPIN (-2900 6100) $PN 1
J 2
(-2910 6080);
DISPLAY 0.489362 (-2910 6080);
PAINT MONO (-2910 6080);
FORCEPROP 1 LASTPIN (-2900 5900) $PN 2
J 2
(-2910 5880);
DISPLAY 0.489362 (-2910 5880);
PAINT MONO (-2910 5880);
FORCEPROP 1 LAST MATERIAL X6S
J 2
(-2950 5900);
DISPLAY 0.489362 (-2950 5900);
PAINT SKYBLUE (-2950 5900);
FORCEPROP 1 LAST TOLERANCE 10%
J 2
(-2950 5950);
DISPLAY 0.489362 (-2950 5950);
PAINT SKYBLUE (-2950 5950);
FORCEPROP 1 LAST VALUE 10UF
J 2
(-2950 6050);
DISPLAY 0.489362 (-2950 6050);
PAINT SKYBLUE (-2950 6050);
FORCEPROP 1 LAST VOLTAGE 25V
J 2
(-2950 6000);
DISPLAY 0.489362 (-2950 6000);
PAINT SKYBLUE (-2950 6000);
FORCEPROP 1 LAST PACK_TYPE C0805
J 2
(-2950 5800);
DISPLAY 0.489362 (-2950 5800);
PAINT SKYBLUE (-2950 5800);
FORCEPROP 1 LAST PART_NUMBER CH6104KEA00
J 2
(-2950 5850);
DISPLAY 0.489362 (-2950 5850);
PAINT SKYBLUE (-2950 5850);
FORCEPROP 0 LAST BOM_COST MEM
J 2
(-2955 6145);
DISPLAY 0.595745 (-2955 6145);
PAINT MONO (-2955 6145);
DISPLAY INVISIBLE (-2955 6145);
FORCEPROP 2 LAST CDS_LIB pure_quanta
J 0
(-2900 6000);
DISPLAY INVISIBLE (-2900 6000);
FORCEPROP 1 LAST PATH I238
J 2
(-2950 6150);
DISPLAY 0.978723 (-2950 6150);
PAINT WHITE (-2950 6150);
DISPLAY INVISIBLE (-2950 6150);
FORCEPROP 0 LAST ROOM MEM_CH_A_CPU0_DIMM1
J 2
(-2955 6145);
DISPLAY 0.595745 (-2955 6145);
PAINT RED (-2955 6145);
DISPLAY INVISIBLE (-2955 6145);
FORCEADD Q_CAP..1
R 2
(-2325 6000);
FORCEPROP 1 LAST LOCATION C527
J 2
(-2375 6100);
DISPLAY 0.489362 (-2375 6100);
PAINT SKYBLUE (-2375 6100);
FORCEPROP 0 LAST $SEC 1
J 0
(-2375 6150);
DISPLAY 0.680851 (-2375 6150);
PAINT MONO (-2375 6150);
DISPLAY INVISIBLE (-2375 6150);
FORCEPROP 0 LAST CDS_SEC 1
J 0
(-2375 6150);
DISPLAY 0.680851 (-2375 6150);
DISPLAY INVISIBLE (-2375 6150);
FORCEPROP 1 LASTPIN (-2325 6100) $PN 1
J 2
(-2335 6080);
DISPLAY 0.489362 (-2335 6080);
PAINT MONO (-2335 6080);
FORCEPROP 1 LASTPIN (-2325 5900) $PN 2
J 2
(-2335 5880);
DISPLAY 0.489362 (-2335 5880);
PAINT MONO (-2335 5880);
FORCEPROP 1 LAST MATERIAL X6S
J 2
(-2375 5900);
DISPLAY 0.489362 (-2375 5900);
PAINT SKYBLUE (-2375 5900);
FORCEPROP 1 LAST TOLERANCE 10%
J 2
(-2375 5950);
DISPLAY 0.489362 (-2375 5950);
PAINT SKYBLUE (-2375 5950);
FORCEPROP 1 LAST VALUE 10UF
J 2
(-2375 6050);
DISPLAY 0.489362 (-2375 6050);
PAINT SKYBLUE (-2375 6050);
FORCEPROP 1 LAST PART_NUMBER CH6104KEA00
J 2
(-2375 5850);
DISPLAY 0.489362 (-2375 5850);
PAINT SKYBLUE (-2375 5850);
FORCEPROP 1 LAST VOLTAGE 25V
J 2
(-2375 6000);
DISPLAY 0.489362 (-2375 6000);
PAINT SKYBLUE (-2375 6000);
FORCEPROP 1 LAST PACK_TYPE C0805
J 2
(-2375 5800);
DISPLAY 0.489362 (-2375 5800);
PAINT SKYBLUE (-2375 5800);
FORCEPROP 0 LAST BOM_COST MEM
J 2
(-2380 6145);
DISPLAY 0.595745 (-2380 6145);
PAINT MONO (-2380 6145);
DISPLAY INVISIBLE (-2380 6145);
FORCEPROP 2 LAST CDS_LIB pure_quanta
J 0
(-2325 6000);
DISPLAY INVISIBLE (-2325 6000);
FORCEPROP 1 LAST PATH I239
J 2
(-2375 6150);
DISPLAY 0.978723 (-2375 6150);
PAINT WHITE (-2375 6150);
DISPLAY INVISIBLE (-2375 6150);
FORCEPROP 0 LAST ROOM MEM_CH_A_CPU0_DIMM1
J 2
(-2380 6145);
DISPLAY 0.595745 (-2380 6145);
PAINT RED (-2380 6145);
DISPLAY INVISIBLE (-2380 6145);
FORCEADD TAP..1
R 2
(-7825 3375);
FORCEPROP 3 LASTPIN (-7775 3375) SIG_NAME M_F_CPU1_SB_CB<1>
J 0
(-7765 3385);
DISPLAY 0.659574 (-7765 3385);
PAINT MONO (-7765 3385);
DISPLAY INVISIBLE (-7765 3385);
FORCEPROP 1 LASTPIN (-7775 3375) BN 1
J 2
(-7763 3383);
DISPLAY 0.489362 (-7763 3383);
PAINT GREEN (-7763 3383);
FORCEPROP 2 LAST CDS_LIB mstr_standard
J 0
(-7825 3375);
DISPLAY 0.723404 (-7825 3375);
PAINT MONO (-7825 3375);
DISPLAY INVISIBLE (-7825 3375);
FORCEPROP 1 LAST BODY_TYPE PLUMBING
J 2
(-7825 3425);
DISPLAY 0.872340 (-7825 3425);
PAINT GREEN (-7825 3425);
DISPLAY INVISIBLE (-7825 3425);
FORCEPROP 1 LAST HDL_TAP TRUE
J 2
(-8150 3250);
DISPLAY 0.872340 (-8150 3250);
DISPLAY INVISIBLE (-8150 3250);
FORCEPROP 1 LAST PATH I24
J 2
(-7823 3375);
DISPLAY 0.872340 (-7823 3375);
PAINT GREEN (-7823 3375);
DISPLAY INVISIBLE (-7823 3375);
FORCEADD UNIVERSAL_POWER..1
(-2900 6325);
FORCEPROP 3 LASTPIN (-2900 6275) SIG_NAME P12V_MEM_2\g
J 0
(-2890 6285);
DISPLAY 0.659574 (-2890 6285);
PAINT MONO (-2890 6285);
DISPLAY INVISIBLE (-2890 6285);
FORCEPROP 1 LAST HDL_POWER P12V_MEM_2
J 1
(-2900 6375);
DISPLAY 0.489362 (-2900 6375);
PAINT GREEN (-2900 6375);
FORCEPROP 2 LAST CDS_LIB pure_quanta_power
J 0
(-2900 6325);
DISPLAY INVISIBLE (-2900 6325);
FORCEPROP 1 LAST PATH I240
J 0
(-2850 6350);
DISPLAY 0.872340 (-2850 6350);
PAINT AQUA (-2850 6350);
DISPLAY INVISIBLE (-2850 6350);
FORCEADD OFFPAGE..1
(-8450 2825);
FORCEPROP 2 LAST $XR5 101 
J 0
(-9212 2825);
DISPLAY 0.638298 (-9212 2825);
PAINT MONO (-9212 2825);
FORCEPROP 2 LAST $XR4 100 
J 0
(-9092 2825);
DISPLAY 0.638298 (-9092 2825);
PAINT MONO (-9092 2825);
FORCEPROP 2 LAST $XR3 99 
J 0
(-8972 2825);
DISPLAY 0.638298 (-8972 2825);
PAINT MONO (-8972 2825);
FORCEPROP 2 LAST $XR2 98 
J 0
(-8882 2825);
DISPLAY 0.638298 (-8882 2825);
PAINT MONO (-8882 2825);
FORCEPROP 2 LAST $XR1 97 
J 0
(-8792 2825);
DISPLAY 0.638298 (-8792 2825);
PAINT MONO (-8792 2825);
FORCEPROP 2 LAST $XR0 136 
J 0
(-8702 2825);
DISPLAY 0.638298 (-8702 2825);
PAINT MONO (-8702 2825);
FORCEPROP 2 LAST PATH I241
J 0
(-8725 2875);
DISPLAY 0.680851 (-8725 2875);
DISPLAY INVISIBLE (-8725 2875);
FORCEPROP 1 LAST COMMENT_BODY TRUE
J 0
(-8325 2725);
DISPLAY 0.872340 (-8325 2725);
PAINT GREEN (-8325 2725);
DISPLAY INVISIBLE (-8325 2725);
FORCEPROP 1 LAST OFFPAGE TRUE
J 0
(-8125 2700);
DISPLAY 0.872340 (-8125 2700);
PAINT GREEN (-8125 2700);
DISPLAY INVISIBLE (-8125 2700);
FORCEPROP 2 LAST CDS_LIB mstr_standard
J 0
(-8450 2825);
DISPLAY 0.808511 (-8450 2825);
DISPLAY INVISIBLE (-8450 2825);
FORCEADD Q_RES..1
(-7875 2825);
FORCEPROP 1 LAST $LOCATION R1585
J 0
(-7925 2850);
DISPLAY 0.510638 (-7925 2850);
PAINT SKYBLUE (-7925 2850);
FORCEPROP 0 LAST CDS_LOCATION R1585
J 0
(-7925 2925);
DISPLAY 0.680851 (-7925 2925);
DISPLAY INVISIBLE (-7925 2925);
FORCEPROP 0 LAST $SEC 1
J 0
(-7925 2925);
DISPLAY 0.680851 (-7925 2925);
PAINT MONO (-7925 2925);
DISPLAY INVISIBLE (-7925 2925);
FORCEPROP 0 LAST CDS_SEC 1
J 0
(-7925 2925);
DISPLAY 0.680851 (-7925 2925);
DISPLAY INVISIBLE (-7925 2925);
FORCEPROP 1 LASTPIN (-7975 2825) $PN 1
J 0
(-7963 2837);
DISPLAY 0.787234 (-7963 2837);
PAINT MONO (-7963 2837);
FORCEPROP 1 LASTPIN (-7775 2825) $PN 2
J 0
(-7813 2837);
DISPLAY 0.787234 (-7813 2837);
PAINT MONO (-7813 2837);
FORCEPROP 1 LAST VALUE 49.9
J 2
(-7725 2875);
DISPLAY 0.510638 (-7725 2875);
PAINT SKYBLUE (-7725 2875);
FORCEPROP 2 LAST CDS_LIB pure_quanta
J 0
(-7875 2825);
DISPLAY INVISIBLE (-7875 2825);
FORCEPROP 1 LAST PATH I242
J 0
(-7925 2975);
DISPLAY 0.978723 (-7925 2975);
PAINT WHITE (-7925 2975);
DISPLAY INVISIBLE (-7925 2975);
FORCEPROP 1 LAST MATERIAL CHIP
J 0
(-7875 2675);
DISPLAY 0.978723 (-7875 2675);
DISPLAY INVISIBLE (-7875 2675);
FORCEPROP 1 LAST PACK_TYPE 0402LF
J 0
(-7625 2675);
DISPLAY 0.978723 (-7625 2675);
DISPLAY INVISIBLE (-7625 2675);
FORCEPROP 1 LAST WATTAGE 1/16W
J 2
(-7900 2675);
DISPLAY 0.978723 (-7900 2675);
DISPLAY INVISIBLE (-7900 2675);
FORCEPROP 1 LAST TOLERANCE 1%
J 0
(-7875 2725);
DISPLAY 0.978723 (-7875 2725);
DISPLAY INVISIBLE (-7875 2725);
FORCEPROP 1 LAST PART_NUMBER CS04992FB07
J 0
(-7925 2925);
DISPLAY 0.978723 (-7925 2925);
DISPLAY INVISIBLE (-7925 2925);
FORCEADD TAP..1
R 2
(-7825 3425);
FORCEPROP 3 LASTPIN (-7775 3425) SIG_NAME M_F_CPU1_SB_CB<2>
J 0
(-7765 3435);
DISPLAY 0.659574 (-7765 3435);
PAINT MONO (-7765 3435);
DISPLAY INVISIBLE (-7765 3435);
FORCEPROP 1 LASTPIN (-7775 3425) BN 2
J 2
(-7763 3433);
DISPLAY 0.489362 (-7763 3433);
PAINT GREEN (-7763 3433);
FORCEPROP 2 LAST CDS_LIB mstr_standard
J 0
(-7825 3425);
DISPLAY 0.723404 (-7825 3425);
PAINT MONO (-7825 3425);
DISPLAY INVISIBLE (-7825 3425);
FORCEPROP 1 LAST BODY_TYPE PLUMBING
J 2
(-7825 3475);
DISPLAY 0.872340 (-7825 3475);
PAINT GREEN (-7825 3475);
DISPLAY INVISIBLE (-7825 3475);
FORCEPROP 1 LAST HDL_TAP TRUE
J 2
(-8150 3300);
DISPLAY 0.872340 (-8150 3300);
DISPLAY INVISIBLE (-8150 3300);
FORCEPROP 1 LAST PATH I25
J 2
(-7823 3425);
DISPLAY 0.872340 (-7823 3425);
PAINT GREEN (-7823 3425);
DISPLAY INVISIBLE (-7823 3425);
FORCEADD TAP..1
R 2
(-7825 3475);
FORCEPROP 3 LASTPIN (-7775 3475) SIG_NAME M_F_CPU1_SB_CB<3>
J 0
(-7765 3485);
DISPLAY 0.659574 (-7765 3485);
PAINT MONO (-7765 3485);
DISPLAY INVISIBLE (-7765 3485);
FORCEPROP 1 LASTPIN (-7775 3475) BN 3
J 2
(-7763 3483);
DISPLAY 0.489362 (-7763 3483);
PAINT GREEN (-7763 3483);
FORCEPROP 2 LAST CDS_LIB mstr_standard
J 0
(-7825 3475);
DISPLAY 0.723404 (-7825 3475);
PAINT MONO (-7825 3475);
DISPLAY INVISIBLE (-7825 3475);
FORCEPROP 1 LAST BODY_TYPE PLUMBING
J 2
(-7825 3525);
DISPLAY 0.872340 (-7825 3525);
PAINT GREEN (-7825 3525);
DISPLAY INVISIBLE (-7825 3525);
FORCEPROP 1 LAST HDL_TAP TRUE
J 2
(-8150 3350);
DISPLAY 0.872340 (-8150 3350);
DISPLAY INVISIBLE (-8150 3350);
FORCEPROP 1 LAST PATH I26
J 2
(-7823 3475);
DISPLAY 0.872340 (-7823 3475);
PAINT GREEN (-7823 3475);
DISPLAY INVISIBLE (-7823 3475);
FORCEADD TAP..1
R 2
(-7825 3525);
FORCEPROP 3 LASTPIN (-7775 3525) SIG_NAME M_F_CPU1_SB_CB<4>
J 0
(-7765 3535);
DISPLAY 0.659574 (-7765 3535);
PAINT MONO (-7765 3535);
DISPLAY INVISIBLE (-7765 3535);
FORCEPROP 1 LASTPIN (-7775 3525) BN 4
J 2
(-7763 3533);
DISPLAY 0.489362 (-7763 3533);
PAINT GREEN (-7763 3533);
FORCEPROP 2 LAST CDS_LIB mstr_standard
J 0
(-7825 3525);
DISPLAY 0.723404 (-7825 3525);
PAINT MONO (-7825 3525);
DISPLAY INVISIBLE (-7825 3525);
FORCEPROP 1 LAST BODY_TYPE PLUMBING
J 2
(-7825 3575);
DISPLAY 0.872340 (-7825 3575);
PAINT GREEN (-7825 3575);
DISPLAY INVISIBLE (-7825 3575);
FORCEPROP 1 LAST HDL_TAP TRUE
J 2
(-8150 3400);
DISPLAY 0.872340 (-8150 3400);
DISPLAY INVISIBLE (-8150 3400);
FORCEPROP 1 LAST PATH I27
J 2
(-7823 3525);
DISPLAY 0.872340 (-7823 3525);
PAINT GREEN (-7823 3525);
DISPLAY INVISIBLE (-7823 3525);
FORCEADD TAP..1
R 2
(-7825 3625);
FORCEPROP 3 LASTPIN (-7775 3625) SIG_NAME M_F_CPU1_SB_CB<6>
J 0
(-7765 3635);
DISPLAY 0.659574 (-7765 3635);
PAINT MONO (-7765 3635);
DISPLAY INVISIBLE (-7765 3635);
FORCEPROP 1 LASTPIN (-7775 3625) BN 6
J 2
(-7763 3633);
DISPLAY 0.489362 (-7763 3633);
PAINT GREEN (-7763 3633);
FORCEPROP 2 LAST CDS_LIB mstr_standard
J 0
(-7825 3625);
DISPLAY 0.723404 (-7825 3625);
PAINT MONO (-7825 3625);
DISPLAY INVISIBLE (-7825 3625);
FORCEPROP 1 LAST BODY_TYPE PLUMBING
J 2
(-7825 3675);
DISPLAY 0.872340 (-7825 3675);
PAINT GREEN (-7825 3675);
DISPLAY INVISIBLE (-7825 3675);
FORCEPROP 1 LAST HDL_TAP TRUE
J 2
(-8150 3500);
DISPLAY 0.872340 (-8150 3500);
DISPLAY INVISIBLE (-8150 3500);
FORCEPROP 1 LAST PATH I28
J 2
(-7823 3625);
DISPLAY 0.872340 (-7823 3625);
PAINT GREEN (-7823 3625);
DISPLAY INVISIBLE (-7823 3625);
FORCEADD TAP..1
R 2
(-7825 3575);
FORCEPROP 3 LASTPIN (-7775 3575) SIG_NAME M_F_CPU1_SB_CB<5>
J 0
(-7765 3585);
DISPLAY 0.659574 (-7765 3585);
PAINT MONO (-7765 3585);
DISPLAY INVISIBLE (-7765 3585);
FORCEPROP 1 LASTPIN (-7775 3575) BN 5
J 2
(-7763 3583);
DISPLAY 0.489362 (-7763 3583);
PAINT GREEN (-7763 3583);
FORCEPROP 2 LAST CDS_LIB mstr_standard
J 0
(-7825 3575);
DISPLAY 0.723404 (-7825 3575);
PAINT MONO (-7825 3575);
DISPLAY INVISIBLE (-7825 3575);
FORCEPROP 1 LAST BODY_TYPE PLUMBING
J 2
(-7825 3625);
DISPLAY 0.872340 (-7825 3625);
PAINT GREEN (-7825 3625);
DISPLAY INVISIBLE (-7825 3625);
FORCEPROP 1 LAST HDL_TAP TRUE
J 2
(-8150 3450);
DISPLAY 0.872340 (-8150 3450);
DISPLAY INVISIBLE (-8150 3450);
FORCEPROP 1 LAST PATH I29
J 2
(-7823 3575);
DISPLAY 0.872340 (-7823 3575);
PAINT GREEN (-7823 3575);
DISPLAY INVISIBLE (-7823 3575);
FORCEADD TAP..1
R 2
(-7825 3675);
FORCEPROP 3 LASTPIN (-7775 3675) SIG_NAME M_F_CPU1_SB_CB<7>
J 0
(-7765 3685);
DISPLAY 0.659574 (-7765 3685);
PAINT MONO (-7765 3685);
DISPLAY INVISIBLE (-7765 3685);
FORCEPROP 1 LASTPIN (-7775 3675) BN 7
J 2
(-7763 3683);
DISPLAY 0.489362 (-7763 3683);
PAINT GREEN (-7763 3683);
FORCEPROP 2 LAST CDS_LIB mstr_standard
J 0
(-7825 3675);
DISPLAY 0.723404 (-7825 3675);
PAINT MONO (-7825 3675);
DISPLAY INVISIBLE (-7825 3675);
FORCEPROP 1 LAST BODY_TYPE PLUMBING
J 2
(-7825 3725);
DISPLAY 0.872340 (-7825 3725);
PAINT GREEN (-7825 3725);
DISPLAY INVISIBLE (-7825 3725);
FORCEPROP 1 LAST HDL_TAP TRUE
J 2
(-8150 3550);
DISPLAY 0.872340 (-8150 3550);
DISPLAY INVISIBLE (-8150 3550);
FORCEPROP 1 LAST PATH I30
J 2
(-7823 3675);
DISPLAY 0.872340 (-7823 3675);
PAINT GREEN (-7823 3675);
DISPLAY INVISIBLE (-7823 3675);
FORCEADD TAP..1
R 2
(-7825 3775);
FORCEPROP 3 LASTPIN (-7775 3775) SIG_NAME M_F_CPU1_SA_CB<0>
J 0
(-7765 3785);
DISPLAY 0.659574 (-7765 3785);
PAINT MONO (-7765 3785);
DISPLAY INVISIBLE (-7765 3785);
FORCEPROP 1 LASTPIN (-7775 3775) BN 0
J 2
(-7763 3783);
DISPLAY 0.489362 (-7763 3783);
PAINT GREEN (-7763 3783);
FORCEPROP 2 LAST CDS_LIB mstr_standard
J 0
(-7825 3775);
DISPLAY 0.723404 (-7825 3775);
PAINT MONO (-7825 3775);
DISPLAY INVISIBLE (-7825 3775);
FORCEPROP 1 LAST BODY_TYPE PLUMBING
J 2
(-7825 3825);
DISPLAY 0.872340 (-7825 3825);
PAINT GREEN (-7825 3825);
DISPLAY INVISIBLE (-7825 3825);
FORCEPROP 1 LAST HDL_TAP TRUE
J 2
(-8150 3650);
DISPLAY 0.872340 (-8150 3650);
DISPLAY INVISIBLE (-8150 3650);
FORCEPROP 1 LAST PATH I31
J 2
(-7823 3775);
DISPLAY 0.872340 (-7823 3775);
PAINT GREEN (-7823 3775);
DISPLAY INVISIBLE (-7823 3775);
FORCEADD TAP..1
R 2
(-7825 3825);
FORCEPROP 3 LASTPIN (-7775 3825) SIG_NAME M_F_CPU1_SA_CB<1>
J 0
(-7765 3835);
DISPLAY 0.659574 (-7765 3835);
PAINT MONO (-7765 3835);
DISPLAY INVISIBLE (-7765 3835);
FORCEPROP 1 LASTPIN (-7775 3825) BN 1
J 2
(-7763 3833);
DISPLAY 0.489362 (-7763 3833);
PAINT GREEN (-7763 3833);
FORCEPROP 2 LAST CDS_LIB mstr_standard
J 0
(-7825 3825);
DISPLAY 0.723404 (-7825 3825);
PAINT MONO (-7825 3825);
DISPLAY INVISIBLE (-7825 3825);
FORCEPROP 1 LAST BODY_TYPE PLUMBING
J 2
(-7825 3875);
DISPLAY 0.872340 (-7825 3875);
PAINT GREEN (-7825 3875);
DISPLAY INVISIBLE (-7825 3875);
FORCEPROP 1 LAST HDL_TAP TRUE
J 2
(-8150 3700);
DISPLAY 0.872340 (-8150 3700);
DISPLAY INVISIBLE (-8150 3700);
FORCEPROP 1 LAST PATH I32
J 2
(-7823 3825);
DISPLAY 0.872340 (-7823 3825);
PAINT GREEN (-7823 3825);
DISPLAY INVISIBLE (-7823 3825);
FORCEADD TAP..1
R 2
(-7825 3875);
FORCEPROP 3 LASTPIN (-7775 3875) SIG_NAME M_F_CPU1_SA_CB<2>
J 0
(-7765 3885);
DISPLAY 0.659574 (-7765 3885);
PAINT MONO (-7765 3885);
DISPLAY INVISIBLE (-7765 3885);
FORCEPROP 1 LASTPIN (-7775 3875) BN 2
J 2
(-7763 3883);
DISPLAY 0.489362 (-7763 3883);
PAINT GREEN (-7763 3883);
FORCEPROP 2 LAST CDS_LIB mstr_standard
J 0
(-7825 3875);
DISPLAY 0.723404 (-7825 3875);
PAINT MONO (-7825 3875);
DISPLAY INVISIBLE (-7825 3875);
FORCEPROP 1 LAST BODY_TYPE PLUMBING
J 2
(-7825 3925);
DISPLAY 0.872340 (-7825 3925);
PAINT GREEN (-7825 3925);
DISPLAY INVISIBLE (-7825 3925);
FORCEPROP 1 LAST HDL_TAP TRUE
J 2
(-8150 3750);
DISPLAY 0.872340 (-8150 3750);
DISPLAY INVISIBLE (-8150 3750);
FORCEPROP 1 LAST PATH I33
J 2
(-7823 3875);
DISPLAY 0.872340 (-7823 3875);
PAINT GREEN (-7823 3875);
DISPLAY INVISIBLE (-7823 3875);
FORCEADD TAP..1
R 2
(-7825 3925);
FORCEPROP 3 LASTPIN (-7775 3925) SIG_NAME M_F_CPU1_SA_CB<3>
J 0
(-7765 3935);
DISPLAY 0.659574 (-7765 3935);
PAINT MONO (-7765 3935);
DISPLAY INVISIBLE (-7765 3935);
FORCEPROP 1 LASTPIN (-7775 3925) BN 3
J 2
(-7763 3933);
DISPLAY 0.489362 (-7763 3933);
PAINT GREEN (-7763 3933);
FORCEPROP 2 LAST CDS_LIB mstr_standard
J 0
(-7825 3925);
DISPLAY 0.723404 (-7825 3925);
PAINT MONO (-7825 3925);
DISPLAY INVISIBLE (-7825 3925);
FORCEPROP 1 LAST BODY_TYPE PLUMBING
J 2
(-7825 3975);
DISPLAY 0.872340 (-7825 3975);
PAINT GREEN (-7825 3975);
DISPLAY INVISIBLE (-7825 3975);
FORCEPROP 1 LAST HDL_TAP TRUE
J 2
(-8150 3800);
DISPLAY 0.872340 (-8150 3800);
DISPLAY INVISIBLE (-8150 3800);
FORCEPROP 1 LAST PATH I34
J 2
(-7823 3925);
DISPLAY 0.872340 (-7823 3925);
PAINT GREEN (-7823 3925);
DISPLAY INVISIBLE (-7823 3925);
FORCEADD TAP..1
(-6125 2325);
FORCEPROP 3 LASTPIN (-6175 2325) SIG_NAME M_F_CPU1_SB_DQ<0>
J 0
(-6165 2335);
DISPLAY 0.659574 (-6165 2335);
PAINT MONO (-6165 2335);
DISPLAY INVISIBLE (-6165 2335);
FORCEPROP 1 LASTPIN (-6175 2325) BN 0
J 0
(-6187 2333);
DISPLAY 0.489362 (-6187 2333);
PAINT GREEN (-6187 2333);
FORCEPROP 2 LAST CDS_LIB mstr_standard
J 0
(-6125 2325);
DISPLAY 0.723404 (-6125 2325);
PAINT MONO (-6125 2325);
DISPLAY INVISIBLE (-6125 2325);
FORCEPROP 1 LAST BODY_TYPE PLUMBING
J 0
(-6125 2375);
DISPLAY 0.872340 (-6125 2375);
PAINT GREEN (-6125 2375);
DISPLAY INVISIBLE (-6125 2375);
FORCEPROP 1 LAST HDL_TAP TRUE
J 0
(-5800 2200);
DISPLAY 0.872340 (-5800 2200);
DISPLAY INVISIBLE (-5800 2200);
FORCEPROP 1 LAST PATH I35
J 0
(-6127 2325);
DISPLAY 0.872340 (-6127 2325);
PAINT GREEN (-6127 2325);
DISPLAY INVISIBLE (-6127 2325);
FORCEADD TAP..1
(-6125 2375);
FORCEPROP 3 LASTPIN (-6175 2375) SIG_NAME M_F_CPU1_SB_DQ<1>
J 0
(-6165 2385);
DISPLAY 0.659574 (-6165 2385);
PAINT MONO (-6165 2385);
DISPLAY INVISIBLE (-6165 2385);
FORCEPROP 1 LASTPIN (-6175 2375) BN 1
J 0
(-6187 2383);
DISPLAY 0.489362 (-6187 2383);
PAINT GREEN (-6187 2383);
FORCEPROP 2 LAST CDS_LIB mstr_standard
J 0
(-6125 2375);
DISPLAY 0.723404 (-6125 2375);
PAINT MONO (-6125 2375);
DISPLAY INVISIBLE (-6125 2375);
FORCEPROP 1 LAST BODY_TYPE PLUMBING
J 0
(-6125 2425);
DISPLAY 0.872340 (-6125 2425);
PAINT GREEN (-6125 2425);
DISPLAY INVISIBLE (-6125 2425);
FORCEPROP 1 LAST HDL_TAP TRUE
J 0
(-5800 2250);
DISPLAY 0.872340 (-5800 2250);
DISPLAY INVISIBLE (-5800 2250);
FORCEPROP 1 LAST PATH I36
J 0
(-6127 2375);
DISPLAY 0.872340 (-6127 2375);
PAINT GREEN (-6127 2375);
DISPLAY INVISIBLE (-6127 2375);
FORCEADD TAP..1
(-6125 2425);
FORCEPROP 3 LASTPIN (-6175 2425) SIG_NAME M_F_CPU1_SB_DQ<2>
J 0
(-6165 2435);
DISPLAY 0.659574 (-6165 2435);
PAINT MONO (-6165 2435);
DISPLAY INVISIBLE (-6165 2435);
FORCEPROP 1 LASTPIN (-6175 2425) BN 2
J 0
(-6187 2433);
DISPLAY 0.489362 (-6187 2433);
PAINT GREEN (-6187 2433);
FORCEPROP 2 LAST CDS_LIB mstr_standard
J 0
(-6125 2425);
DISPLAY 0.723404 (-6125 2425);
PAINT MONO (-6125 2425);
DISPLAY INVISIBLE (-6125 2425);
FORCEPROP 1 LAST BODY_TYPE PLUMBING
J 0
(-6125 2475);
DISPLAY 0.872340 (-6125 2475);
PAINT GREEN (-6125 2475);
DISPLAY INVISIBLE (-6125 2475);
FORCEPROP 1 LAST HDL_TAP TRUE
J 0
(-5800 2300);
DISPLAY 0.872340 (-5800 2300);
DISPLAY INVISIBLE (-5800 2300);
FORCEPROP 1 LAST PATH I37
J 0
(-6127 2425);
DISPLAY 0.872340 (-6127 2425);
PAINT GREEN (-6127 2425);
DISPLAY INVISIBLE (-6127 2425);
FORCEADD TAP..1
(-6125 2475);
FORCEPROP 3 LASTPIN (-6175 2475) SIG_NAME M_F_CPU1_SB_DQ<3>
J 0
(-6165 2485);
DISPLAY 0.659574 (-6165 2485);
PAINT MONO (-6165 2485);
DISPLAY INVISIBLE (-6165 2485);
FORCEPROP 1 LASTPIN (-6175 2475) BN 3
J 0
(-6187 2483);
DISPLAY 0.489362 (-6187 2483);
PAINT GREEN (-6187 2483);
FORCEPROP 2 LAST CDS_LIB mstr_standard
J 0
(-6125 2475);
DISPLAY 0.723404 (-6125 2475);
PAINT MONO (-6125 2475);
DISPLAY INVISIBLE (-6125 2475);
FORCEPROP 1 LAST BODY_TYPE PLUMBING
J 0
(-6125 2525);
DISPLAY 0.872340 (-6125 2525);
PAINT GREEN (-6125 2525);
DISPLAY INVISIBLE (-6125 2525);
FORCEPROP 1 LAST HDL_TAP TRUE
J 0
(-5800 2350);
DISPLAY 0.872340 (-5800 2350);
DISPLAY INVISIBLE (-5800 2350);
FORCEPROP 1 LAST PATH I38
J 0
(-6127 2475);
DISPLAY 0.872340 (-6127 2475);
PAINT GREEN (-6127 2475);
DISPLAY INVISIBLE (-6127 2475);
FORCEADD TAP..1
(-6125 2525);
FORCEPROP 3 LASTPIN (-6175 2525) SIG_NAME M_F_CPU1_SB_DQ<4>
J 0
(-6165 2535);
DISPLAY 0.659574 (-6165 2535);
PAINT MONO (-6165 2535);
DISPLAY INVISIBLE (-6165 2535);
FORCEPROP 1 LASTPIN (-6175 2525) BN 4
J 0
(-6187 2533);
DISPLAY 0.489362 (-6187 2533);
PAINT GREEN (-6187 2533);
FORCEPROP 2 LAST CDS_LIB mstr_standard
J 0
(-6125 2525);
DISPLAY 0.723404 (-6125 2525);
PAINT MONO (-6125 2525);
DISPLAY INVISIBLE (-6125 2525);
FORCEPROP 1 LAST BODY_TYPE PLUMBING
J 0
(-6125 2575);
DISPLAY 0.872340 (-6125 2575);
PAINT GREEN (-6125 2575);
DISPLAY INVISIBLE (-6125 2575);
FORCEPROP 1 LAST HDL_TAP TRUE
J 0
(-5800 2400);
DISPLAY 0.872340 (-5800 2400);
DISPLAY INVISIBLE (-5800 2400);
FORCEPROP 1 LAST PATH I39
J 0
(-6127 2525);
DISPLAY 0.872340 (-6127 2525);
PAINT GREEN (-6127 2525);
DISPLAY INVISIBLE (-6127 2525);
FORCEADD TAP..1
(-6125 2575);
FORCEPROP 3 LASTPIN (-6175 2575) SIG_NAME M_F_CPU1_SB_DQ<5>
J 0
(-6165 2585);
DISPLAY 0.659574 (-6165 2585);
PAINT MONO (-6165 2585);
DISPLAY INVISIBLE (-6165 2585);
FORCEPROP 1 LASTPIN (-6175 2575) BN 5
J 0
(-6187 2583);
DISPLAY 0.489362 (-6187 2583);
PAINT GREEN (-6187 2583);
FORCEPROP 2 LAST CDS_LIB mstr_standard
J 0
(-6125 2575);
DISPLAY 0.723404 (-6125 2575);
PAINT MONO (-6125 2575);
DISPLAY INVISIBLE (-6125 2575);
FORCEPROP 1 LAST BODY_TYPE PLUMBING
J 0
(-6125 2625);
DISPLAY 0.872340 (-6125 2625);
PAINT GREEN (-6125 2625);
DISPLAY INVISIBLE (-6125 2625);
FORCEPROP 1 LAST HDL_TAP TRUE
J 0
(-5800 2450);
DISPLAY 0.872340 (-5800 2450);
DISPLAY INVISIBLE (-5800 2450);
FORCEPROP 1 LAST PATH I40
J 0
(-6127 2575);
DISPLAY 0.872340 (-6127 2575);
PAINT GREEN (-6127 2575);
DISPLAY INVISIBLE (-6127 2575);
FORCEADD TAP..1
(-6125 2625);
FORCEPROP 3 LASTPIN (-6175 2625) SIG_NAME M_F_CPU1_SB_DQ<6>
J 0
(-6165 2635);
DISPLAY 0.659574 (-6165 2635);
PAINT MONO (-6165 2635);
DISPLAY INVISIBLE (-6165 2635);
FORCEPROP 1 LASTPIN (-6175 2625) BN 6
J 0
(-6187 2633);
DISPLAY 0.489362 (-6187 2633);
PAINT GREEN (-6187 2633);
FORCEPROP 2 LAST CDS_LIB mstr_standard
J 0
(-6125 2625);
DISPLAY 0.723404 (-6125 2625);
PAINT MONO (-6125 2625);
DISPLAY INVISIBLE (-6125 2625);
FORCEPROP 1 LAST BODY_TYPE PLUMBING
J 0
(-6125 2675);
DISPLAY 0.872340 (-6125 2675);
PAINT GREEN (-6125 2675);
DISPLAY INVISIBLE (-6125 2675);
FORCEPROP 1 LAST HDL_TAP TRUE
J 0
(-5800 2500);
DISPLAY 0.872340 (-5800 2500);
DISPLAY INVISIBLE (-5800 2500);
FORCEPROP 1 LAST PATH I41
J 0
(-6127 2625);
DISPLAY 0.872340 (-6127 2625);
PAINT GREEN (-6127 2625);
DISPLAY INVISIBLE (-6127 2625);
FORCEADD TAP..1
(-6125 2675);
FORCEPROP 3 LASTPIN (-6175 2675) SIG_NAME M_F_CPU1_SB_DQ<7>
J 0
(-6165 2685);
DISPLAY 0.659574 (-6165 2685);
PAINT MONO (-6165 2685);
DISPLAY INVISIBLE (-6165 2685);
FORCEPROP 1 LASTPIN (-6175 2675) BN 7
J 0
(-6187 2683);
DISPLAY 0.489362 (-6187 2683);
PAINT GREEN (-6187 2683);
FORCEPROP 2 LAST CDS_LIB mstr_standard
J 0
(-6125 2675);
DISPLAY 0.723404 (-6125 2675);
PAINT MONO (-6125 2675);
DISPLAY INVISIBLE (-6125 2675);
FORCEPROP 1 LAST BODY_TYPE PLUMBING
J 0
(-6125 2725);
DISPLAY 0.872340 (-6125 2725);
PAINT GREEN (-6125 2725);
DISPLAY INVISIBLE (-6125 2725);
FORCEPROP 1 LAST HDL_TAP TRUE
J 0
(-5800 2550);
DISPLAY 0.872340 (-5800 2550);
DISPLAY INVISIBLE (-5800 2550);
FORCEPROP 1 LAST PATH I42
J 0
(-6127 2675);
DISPLAY 0.872340 (-6127 2675);
PAINT GREEN (-6127 2675);
DISPLAY INVISIBLE (-6127 2675);
FORCEADD TAP..1
(-6125 2725);
FORCEPROP 3 LASTPIN (-6175 2725) SIG_NAME M_F_CPU1_SB_DQ<8>
J 0
(-6165 2735);
DISPLAY 0.659574 (-6165 2735);
PAINT MONO (-6165 2735);
DISPLAY INVISIBLE (-6165 2735);
FORCEPROP 1 LASTPIN (-6175 2725) BN 8
J 0
(-6187 2733);
DISPLAY 0.489362 (-6187 2733);
PAINT GREEN (-6187 2733);
FORCEPROP 2 LAST CDS_LIB mstr_standard
J 0
(-6125 2725);
DISPLAY 0.723404 (-6125 2725);
PAINT MONO (-6125 2725);
DISPLAY INVISIBLE (-6125 2725);
FORCEPROP 1 LAST BODY_TYPE PLUMBING
J 0
(-6125 2775);
DISPLAY 0.872340 (-6125 2775);
PAINT GREEN (-6125 2775);
DISPLAY INVISIBLE (-6125 2775);
FORCEPROP 1 LAST HDL_TAP TRUE
J 0
(-5800 2600);
DISPLAY 0.872340 (-5800 2600);
DISPLAY INVISIBLE (-5800 2600);
FORCEPROP 1 LAST PATH I43
J 0
(-6127 2725);
DISPLAY 0.872340 (-6127 2725);
PAINT GREEN (-6127 2725);
DISPLAY INVISIBLE (-6127 2725);
FORCEADD TAP..1
(-6125 2775);
FORCEPROP 3 LASTPIN (-6175 2775) SIG_NAME M_F_CPU1_SB_DQ<9>
J 0
(-6165 2785);
DISPLAY 0.659574 (-6165 2785);
PAINT MONO (-6165 2785);
DISPLAY INVISIBLE (-6165 2785);
FORCEPROP 1 LASTPIN (-6175 2775) BN 9
J 0
(-6187 2783);
DISPLAY 0.489362 (-6187 2783);
PAINT GREEN (-6187 2783);
FORCEPROP 2 LAST CDS_LIB mstr_standard
J 0
(-6125 2775);
DISPLAY 0.723404 (-6125 2775);
PAINT MONO (-6125 2775);
DISPLAY INVISIBLE (-6125 2775);
FORCEPROP 1 LAST BODY_TYPE PLUMBING
J 0
(-6125 2825);
DISPLAY 0.872340 (-6125 2825);
PAINT GREEN (-6125 2825);
DISPLAY INVISIBLE (-6125 2825);
FORCEPROP 1 LAST HDL_TAP TRUE
J 0
(-5800 2650);
DISPLAY 0.872340 (-5800 2650);
DISPLAY INVISIBLE (-5800 2650);
FORCEPROP 1 LAST PATH I44
J 0
(-6127 2775);
DISPLAY 0.872340 (-6127 2775);
PAINT GREEN (-6127 2775);
DISPLAY INVISIBLE (-6127 2775);
FORCEADD TAP..1
(-6125 2825);
FORCEPROP 3 LASTPIN (-6175 2825) SIG_NAME M_F_CPU1_SB_DQ<10>
J 0
(-6165 2835);
DISPLAY 0.659574 (-6165 2835);
PAINT MONO (-6165 2835);
DISPLAY INVISIBLE (-6165 2835);
FORCEPROP 1 LASTPIN (-6175 2825) BN 10
J 0
(-6187 2833);
DISPLAY 0.489362 (-6187 2833);
PAINT GREEN (-6187 2833);
FORCEPROP 2 LAST CDS_LIB mstr_standard
J 0
(-6125 2825);
DISPLAY 0.723404 (-6125 2825);
PAINT MONO (-6125 2825);
DISPLAY INVISIBLE (-6125 2825);
FORCEPROP 1 LAST BODY_TYPE PLUMBING
J 0
(-6125 2875);
DISPLAY 0.872340 (-6125 2875);
PAINT GREEN (-6125 2875);
DISPLAY INVISIBLE (-6125 2875);
FORCEPROP 1 LAST HDL_TAP TRUE
J 0
(-5800 2700);
DISPLAY 0.872340 (-5800 2700);
DISPLAY INVISIBLE (-5800 2700);
FORCEPROP 1 LAST PATH I45
J 0
(-6127 2825);
DISPLAY 0.872340 (-6127 2825);
PAINT GREEN (-6127 2825);
DISPLAY INVISIBLE (-6127 2825);
FORCEADD TAP..1
(-6125 2875);
FORCEPROP 3 LASTPIN (-6175 2875) SIG_NAME M_F_CPU1_SB_DQ<11>
J 0
(-6165 2885);
DISPLAY 0.659574 (-6165 2885);
PAINT MONO (-6165 2885);
DISPLAY INVISIBLE (-6165 2885);
FORCEPROP 1 LASTPIN (-6175 2875) BN 11
J 0
(-6187 2883);
DISPLAY 0.489362 (-6187 2883);
PAINT GREEN (-6187 2883);
FORCEPROP 2 LAST CDS_LIB mstr_standard
J 0
(-6125 2875);
DISPLAY 0.723404 (-6125 2875);
PAINT MONO (-6125 2875);
DISPLAY INVISIBLE (-6125 2875);
FORCEPROP 1 LAST BODY_TYPE PLUMBING
J 0
(-6125 2925);
DISPLAY 0.872340 (-6125 2925);
PAINT GREEN (-6125 2925);
DISPLAY INVISIBLE (-6125 2925);
FORCEPROP 1 LAST HDL_TAP TRUE
J 0
(-5800 2750);
DISPLAY 0.872340 (-5800 2750);
DISPLAY INVISIBLE (-5800 2750);
FORCEPROP 1 LAST PATH I46
J 0
(-6127 2875);
DISPLAY 0.872340 (-6127 2875);
PAINT GREEN (-6127 2875);
DISPLAY INVISIBLE (-6127 2875);
FORCEADD TAP..1
(-6125 2925);
FORCEPROP 3 LASTPIN (-6175 2925) SIG_NAME M_F_CPU1_SB_DQ<12>
J 0
(-6165 2935);
DISPLAY 0.659574 (-6165 2935);
PAINT MONO (-6165 2935);
DISPLAY INVISIBLE (-6165 2935);
FORCEPROP 1 LASTPIN (-6175 2925) BN 12
J 0
(-6187 2933);
DISPLAY 0.489362 (-6187 2933);
PAINT GREEN (-6187 2933);
FORCEPROP 2 LAST CDS_LIB mstr_standard
J 0
(-6125 2925);
DISPLAY 0.723404 (-6125 2925);
PAINT MONO (-6125 2925);
DISPLAY INVISIBLE (-6125 2925);
FORCEPROP 1 LAST BODY_TYPE PLUMBING
J 0
(-6125 2975);
DISPLAY 0.872340 (-6125 2975);
PAINT GREEN (-6125 2975);
DISPLAY INVISIBLE (-6125 2975);
FORCEPROP 1 LAST HDL_TAP TRUE
J 0
(-5800 2800);
DISPLAY 0.872340 (-5800 2800);
DISPLAY INVISIBLE (-5800 2800);
FORCEPROP 1 LAST PATH I47
J 0
(-6127 2925);
DISPLAY 0.872340 (-6127 2925);
PAINT GREEN (-6127 2925);
DISPLAY INVISIBLE (-6127 2925);
FORCEADD TAP..1
(-6125 2975);
FORCEPROP 3 LASTPIN (-6175 2975) SIG_NAME M_F_CPU1_SB_DQ<13>
J 0
(-6165 2985);
DISPLAY 0.659574 (-6165 2985);
PAINT MONO (-6165 2985);
DISPLAY INVISIBLE (-6165 2985);
FORCEPROP 1 LASTPIN (-6175 2975) BN 13
J 0
(-6187 2983);
DISPLAY 0.489362 (-6187 2983);
PAINT GREEN (-6187 2983);
FORCEPROP 2 LAST CDS_LIB mstr_standard
J 0
(-6125 2975);
DISPLAY 0.723404 (-6125 2975);
PAINT MONO (-6125 2975);
DISPLAY INVISIBLE (-6125 2975);
FORCEPROP 1 LAST BODY_TYPE PLUMBING
J 0
(-6125 3025);
DISPLAY 0.872340 (-6125 3025);
PAINT GREEN (-6125 3025);
DISPLAY INVISIBLE (-6125 3025);
FORCEPROP 1 LAST HDL_TAP TRUE
J 0
(-5800 2850);
DISPLAY 0.872340 (-5800 2850);
DISPLAY INVISIBLE (-5800 2850);
FORCEPROP 1 LAST PATH I48
J 0
(-6127 2975);
DISPLAY 0.872340 (-6127 2975);
PAINT GREEN (-6127 2975);
DISPLAY INVISIBLE (-6127 2975);
FORCEADD TAP..1
(-6125 3025);
FORCEPROP 3 LASTPIN (-6175 3025) SIG_NAME M_F_CPU1_SB_DQ<14>
J 0
(-6165 3035);
DISPLAY 0.659574 (-6165 3035);
PAINT MONO (-6165 3035);
DISPLAY INVISIBLE (-6165 3035);
FORCEPROP 1 LASTPIN (-6175 3025) BN 14
J 0
(-6187 3033);
DISPLAY 0.489362 (-6187 3033);
PAINT GREEN (-6187 3033);
FORCEPROP 2 LAST CDS_LIB mstr_standard
J 0
(-6125 3025);
DISPLAY 0.723404 (-6125 3025);
PAINT MONO (-6125 3025);
DISPLAY INVISIBLE (-6125 3025);
FORCEPROP 1 LAST BODY_TYPE PLUMBING
J 0
(-6125 3075);
DISPLAY 0.872340 (-6125 3075);
PAINT GREEN (-6125 3075);
DISPLAY INVISIBLE (-6125 3075);
FORCEPROP 1 LAST HDL_TAP TRUE
J 0
(-5800 2900);
DISPLAY 0.872340 (-5800 2900);
DISPLAY INVISIBLE (-5800 2900);
FORCEPROP 1 LAST PATH I49
J 0
(-6127 3025);
DISPLAY 0.872340 (-6127 3025);
PAINT GREEN (-6127 3025);
DISPLAY INVISIBLE (-6127 3025);
FORCEADD VCC_CORE..1
(-8575 3550);
FORCEPROP 3 LASTPIN (-8575 3500) SIG_NAME P3V3_STBY\g
J 0
(-8565 3510);
DISPLAY 0.659574 (-8565 3510);
PAINT MONO (-8565 3510);
DISPLAY INVISIBLE (-8565 3510);
FORCEPROP 1 LAST HDL_POWER P3V3_STBY
J 1
(-8575 3600);
DISPLAY 0.489362 (-8575 3600);
PAINT GREEN (-8575 3600);
FORCEPROP 2 LAST CDS_LIB mstr_symbols
J 0
(-8575 3550);
PAINT MONO (-8575 3550);
DISPLAY INVISIBLE (-8575 3550);
FORCEPROP 1 LAST PATH I5
J 0
(-8525 3575);
DISPLAY 0.872340 (-8525 3575);
PAINT AQUA (-8525 3575);
DISPLAY INVISIBLE (-8525 3575);
FORCEPROP 0 LAST VOLTAGE 3.3
J 0
(-8850 3700);
DISPLAY 1.021277 (-8850 3700);
PAINT SKYBLUE (-8850 3700);
DISPLAY INVISIBLE (-8850 3700);
FORCEPROP 2 LAST ROOM PVCCINFAON_CPU1_CTRL
J 0
(-8575 3650);
DISPLAY 0.808511 (-8575 3650);
PAINT RED (-8575 3650);
DISPLAY INVISIBLE (-8575 3650);
FORCEADD TAP..1
(-6125 3125);
FORCEPROP 3 LASTPIN (-6175 3125) SIG_NAME M_F_CPU1_SB_DQ<16>
J 0
(-6165 3135);
DISPLAY 0.659574 (-6165 3135);
PAINT MONO (-6165 3135);
DISPLAY INVISIBLE (-6165 3135);
FORCEPROP 1 LASTPIN (-6175 3125) BN 16
J 0
(-6187 3133);
DISPLAY 0.489362 (-6187 3133);
PAINT GREEN (-6187 3133);
FORCEPROP 2 LAST CDS_LIB mstr_standard
J 0
(-6125 3125);
DISPLAY 0.723404 (-6125 3125);
PAINT MONO (-6125 3125);
DISPLAY INVISIBLE (-6125 3125);
FORCEPROP 1 LAST BODY_TYPE PLUMBING
J 0
(-6125 3175);
DISPLAY 0.872340 (-6125 3175);
PAINT GREEN (-6125 3175);
DISPLAY INVISIBLE (-6125 3175);
FORCEPROP 1 LAST HDL_TAP TRUE
J 0
(-5800 3000);
DISPLAY 0.872340 (-5800 3000);
DISPLAY INVISIBLE (-5800 3000);
FORCEPROP 1 LAST PATH I50
J 0
(-6127 3125);
DISPLAY 0.872340 (-6127 3125);
PAINT GREEN (-6127 3125);
DISPLAY INVISIBLE (-6127 3125);
FORCEADD TAP..1
(-6125 3075);
FORCEPROP 3 LASTPIN (-6175 3075) SIG_NAME M_F_CPU1_SB_DQ<15>
J 0
(-6165 3085);
DISPLAY 0.659574 (-6165 3085);
PAINT MONO (-6165 3085);
DISPLAY INVISIBLE (-6165 3085);
FORCEPROP 1 LASTPIN (-6175 3075) BN 15
J 0
(-6187 3083);
DISPLAY 0.489362 (-6187 3083);
PAINT GREEN (-6187 3083);
FORCEPROP 2 LAST CDS_LIB mstr_standard
J 0
(-6125 3075);
DISPLAY 0.723404 (-6125 3075);
PAINT MONO (-6125 3075);
DISPLAY INVISIBLE (-6125 3075);
FORCEPROP 1 LAST BODY_TYPE PLUMBING
J 0
(-6125 3125);
DISPLAY 0.872340 (-6125 3125);
PAINT GREEN (-6125 3125);
DISPLAY INVISIBLE (-6125 3125);
FORCEPROP 1 LAST HDL_TAP TRUE
J 0
(-5800 2950);
DISPLAY 0.872340 (-5800 2950);
DISPLAY INVISIBLE (-5800 2950);
FORCEPROP 1 LAST PATH I51
J 0
(-6127 3075);
DISPLAY 0.872340 (-6127 3075);
PAINT GREEN (-6127 3075);
DISPLAY INVISIBLE (-6127 3075);
FORCEADD TAP..1
(-6125 3175);
FORCEPROP 3 LASTPIN (-6175 3175) SIG_NAME M_F_CPU1_SB_DQ<17>
J 0
(-6165 3185);
DISPLAY 0.659574 (-6165 3185);
PAINT MONO (-6165 3185);
DISPLAY INVISIBLE (-6165 3185);
FORCEPROP 1 LASTPIN (-6175 3175) BN 17
J 0
(-6187 3183);
DISPLAY 0.489362 (-6187 3183);
PAINT GREEN (-6187 3183);
FORCEPROP 2 LAST CDS_LIB mstr_standard
J 0
(-6125 3175);
DISPLAY 0.723404 (-6125 3175);
PAINT MONO (-6125 3175);
DISPLAY INVISIBLE (-6125 3175);
FORCEPROP 1 LAST BODY_TYPE PLUMBING
J 0
(-6125 3225);
DISPLAY 0.872340 (-6125 3225);
PAINT GREEN (-6125 3225);
DISPLAY INVISIBLE (-6125 3225);
FORCEPROP 1 LAST HDL_TAP TRUE
J 0
(-5800 3050);
DISPLAY 0.872340 (-5800 3050);
DISPLAY INVISIBLE (-5800 3050);
FORCEPROP 1 LAST PATH I52
J 0
(-6127 3175);
DISPLAY 0.872340 (-6127 3175);
PAINT GREEN (-6127 3175);
DISPLAY INVISIBLE (-6127 3175);
FORCEADD TAP..1
(-6125 3275);
FORCEPROP 3 LASTPIN (-6175 3275) SIG_NAME M_F_CPU1_SB_DQ<19>
J 0
(-6165 3285);
DISPLAY 0.659574 (-6165 3285);
PAINT MONO (-6165 3285);
DISPLAY INVISIBLE (-6165 3285);
FORCEPROP 1 LASTPIN (-6175 3275) BN 19
J 0
(-6187 3283);
DISPLAY 0.489362 (-6187 3283);
PAINT GREEN (-6187 3283);
FORCEPROP 2 LAST CDS_LIB mstr_standard
J 0
(-6125 3275);
DISPLAY 0.723404 (-6125 3275);
PAINT MONO (-6125 3275);
DISPLAY INVISIBLE (-6125 3275);
FORCEPROP 1 LAST BODY_TYPE PLUMBING
J 0
(-6125 3325);
DISPLAY 0.872340 (-6125 3325);
PAINT GREEN (-6125 3325);
DISPLAY INVISIBLE (-6125 3325);
FORCEPROP 1 LAST HDL_TAP TRUE
J 0
(-5800 3150);
DISPLAY 0.872340 (-5800 3150);
DISPLAY INVISIBLE (-5800 3150);
FORCEPROP 1 LAST PATH I53
J 0
(-6127 3275);
DISPLAY 0.872340 (-6127 3275);
PAINT GREEN (-6127 3275);
DISPLAY INVISIBLE (-6127 3275);
FORCEADD TAP..1
(-6125 3325);
FORCEPROP 3 LASTPIN (-6175 3325) SIG_NAME M_F_CPU1_SB_DQ<20>
J 0
(-6165 3335);
DISPLAY 0.659574 (-6165 3335);
PAINT MONO (-6165 3335);
DISPLAY INVISIBLE (-6165 3335);
FORCEPROP 1 LASTPIN (-6175 3325) BN 20
J 0
(-6187 3333);
DISPLAY 0.489362 (-6187 3333);
PAINT GREEN (-6187 3333);
FORCEPROP 2 LAST CDS_LIB mstr_standard
J 0
(-6125 3325);
DISPLAY 0.723404 (-6125 3325);
PAINT MONO (-6125 3325);
DISPLAY INVISIBLE (-6125 3325);
FORCEPROP 1 LAST BODY_TYPE PLUMBING
J 0
(-6125 3375);
DISPLAY 0.872340 (-6125 3375);
PAINT GREEN (-6125 3375);
DISPLAY INVISIBLE (-6125 3375);
FORCEPROP 1 LAST HDL_TAP TRUE
J 0
(-5800 3200);
DISPLAY 0.872340 (-5800 3200);
DISPLAY INVISIBLE (-5800 3200);
FORCEPROP 1 LAST PATH I54
J 0
(-6127 3325);
DISPLAY 0.872340 (-6127 3325);
PAINT GREEN (-6127 3325);
DISPLAY INVISIBLE (-6127 3325);
FORCEADD TAP..1
(-6125 3425);
FORCEPROP 3 LASTPIN (-6175 3425) SIG_NAME M_F_CPU1_SB_DQ<22>
J 0
(-6165 3435);
DISPLAY 0.659574 (-6165 3435);
PAINT MONO (-6165 3435);
DISPLAY INVISIBLE (-6165 3435);
FORCEPROP 1 LASTPIN (-6175 3425) BN 22
J 0
(-6187 3433);
DISPLAY 0.489362 (-6187 3433);
PAINT GREEN (-6187 3433);
FORCEPROP 2 LAST CDS_LIB mstr_standard
J 0
(-6125 3425);
DISPLAY 0.723404 (-6125 3425);
PAINT MONO (-6125 3425);
DISPLAY INVISIBLE (-6125 3425);
FORCEPROP 1 LAST BODY_TYPE PLUMBING
J 0
(-6125 3475);
DISPLAY 0.872340 (-6125 3475);
PAINT GREEN (-6125 3475);
DISPLAY INVISIBLE (-6125 3475);
FORCEPROP 1 LAST HDL_TAP TRUE
J 0
(-5800 3300);
DISPLAY 0.872340 (-5800 3300);
DISPLAY INVISIBLE (-5800 3300);
FORCEPROP 1 LAST PATH I55
J 0
(-6127 3425);
DISPLAY 0.872340 (-6127 3425);
PAINT GREEN (-6127 3425);
DISPLAY INVISIBLE (-6127 3425);
FORCEADD TAP..1
(-6125 3375);
FORCEPROP 3 LASTPIN (-6175 3375) SIG_NAME M_F_CPU1_SB_DQ<21>
J 0
(-6165 3385);
DISPLAY 0.659574 (-6165 3385);
PAINT MONO (-6165 3385);
DISPLAY INVISIBLE (-6165 3385);
FORCEPROP 1 LASTPIN (-6175 3375) BN 21
J 0
(-6187 3383);
DISPLAY 0.489362 (-6187 3383);
PAINT GREEN (-6187 3383);
FORCEPROP 2 LAST CDS_LIB mstr_standard
J 0
(-6125 3375);
DISPLAY 0.723404 (-6125 3375);
PAINT MONO (-6125 3375);
DISPLAY INVISIBLE (-6125 3375);
FORCEPROP 1 LAST BODY_TYPE PLUMBING
J 0
(-6125 3425);
DISPLAY 0.872340 (-6125 3425);
PAINT GREEN (-6125 3425);
DISPLAY INVISIBLE (-6125 3425);
FORCEPROP 1 LAST HDL_TAP TRUE
J 0
(-5800 3250);
DISPLAY 0.872340 (-5800 3250);
DISPLAY INVISIBLE (-5800 3250);
FORCEPROP 1 LAST PATH I56
J 0
(-6127 3375);
DISPLAY 0.872340 (-6127 3375);
PAINT GREEN (-6127 3375);
DISPLAY INVISIBLE (-6127 3375);
FORCEADD TAP..1
(-6125 3225);
FORCEPROP 3 LASTPIN (-6175 3225) SIG_NAME M_F_CPU1_SB_DQ<18>
J 0
(-6165 3235);
DISPLAY 0.659574 (-6165 3235);
PAINT MONO (-6165 3235);
DISPLAY INVISIBLE (-6165 3235);
FORCEPROP 1 LASTPIN (-6175 3225) BN 18
J 0
(-6187 3233);
DISPLAY 0.489362 (-6187 3233);
PAINT GREEN (-6187 3233);
FORCEPROP 2 LAST CDS_LIB mstr_standard
J 0
(-6125 3225);
DISPLAY 0.723404 (-6125 3225);
PAINT MONO (-6125 3225);
DISPLAY INVISIBLE (-6125 3225);
FORCEPROP 1 LAST BODY_TYPE PLUMBING
J 0
(-6125 3275);
DISPLAY 0.872340 (-6125 3275);
PAINT GREEN (-6125 3275);
DISPLAY INVISIBLE (-6125 3275);
FORCEPROP 1 LAST HDL_TAP TRUE
J 0
(-5800 3100);
DISPLAY 0.872340 (-5800 3100);
DISPLAY INVISIBLE (-5800 3100);
FORCEPROP 1 LAST PATH I57
J 0
(-6127 3225);
DISPLAY 0.872340 (-6127 3225);
PAINT GREEN (-6127 3225);
DISPLAY INVISIBLE (-6127 3225);
FORCEADD TAP..1
(-6125 3525);
FORCEPROP 3 LASTPIN (-6175 3525) SIG_NAME M_F_CPU1_SB_DQ<24>
J 0
(-6165 3535);
DISPLAY 0.659574 (-6165 3535);
PAINT MONO (-6165 3535);
DISPLAY INVISIBLE (-6165 3535);
FORCEPROP 1 LASTPIN (-6175 3525) BN 24
J 0
(-6187 3533);
DISPLAY 0.489362 (-6187 3533);
PAINT GREEN (-6187 3533);
FORCEPROP 2 LAST CDS_LIB mstr_standard
J 0
(-6125 3525);
DISPLAY 0.723404 (-6125 3525);
PAINT MONO (-6125 3525);
DISPLAY INVISIBLE (-6125 3525);
FORCEPROP 1 LAST BODY_TYPE PLUMBING
J 0
(-6125 3575);
DISPLAY 0.872340 (-6125 3575);
PAINT GREEN (-6125 3575);
DISPLAY INVISIBLE (-6125 3575);
FORCEPROP 1 LAST HDL_TAP TRUE
J 0
(-5800 3400);
DISPLAY 0.872340 (-5800 3400);
DISPLAY INVISIBLE (-5800 3400);
FORCEPROP 1 LAST PATH I58
J 0
(-6127 3525);
DISPLAY 0.872340 (-6127 3525);
PAINT GREEN (-6127 3525);
DISPLAY INVISIBLE (-6127 3525);
FORCEADD TAP..1
(-6125 3575);
FORCEPROP 3 LASTPIN (-6175 3575) SIG_NAME M_F_CPU1_SB_DQ<25>
J 0
(-6165 3585);
DISPLAY 0.659574 (-6165 3585);
PAINT MONO (-6165 3585);
DISPLAY INVISIBLE (-6165 3585);
FORCEPROP 1 LASTPIN (-6175 3575) BN 25
J 0
(-6187 3583);
DISPLAY 0.489362 (-6187 3583);
PAINT GREEN (-6187 3583);
FORCEPROP 2 LAST CDS_LIB mstr_standard
J 0
(-6125 3575);
DISPLAY 0.723404 (-6125 3575);
PAINT MONO (-6125 3575);
DISPLAY INVISIBLE (-6125 3575);
FORCEPROP 1 LAST BODY_TYPE PLUMBING
J 0
(-6125 3625);
DISPLAY 0.872340 (-6125 3625);
PAINT GREEN (-6125 3625);
DISPLAY INVISIBLE (-6125 3625);
FORCEPROP 1 LAST HDL_TAP TRUE
J 0
(-5800 3450);
DISPLAY 0.872340 (-5800 3450);
DISPLAY INVISIBLE (-5800 3450);
FORCEPROP 1 LAST PATH I59
J 0
(-6127 3575);
DISPLAY 0.872340 (-6127 3575);
PAINT GREEN (-6127 3575);
DISPLAY INVISIBLE (-6127 3575);
FORCEADD OFFPAGE..5
(-8225 3175);
FORCEPROP 2 LAST $XR0 42 
J 0
(-8449 3175);
DISPLAY 0.638298 (-8449 3175);
PAINT MONO (-8449 3175);
FORCEPROP 2 LAST PATH I6
J 0
(-8475 3225);
DISPLAY 1.021277 (-8475 3225);
DISPLAY INVISIBLE (-8475 3225);
FORCEPROP 1 LAST COMMENT_BODY TRUE
J 0
(-8125 3100);
DISPLAY 0.872340 (-8125 3100);
PAINT GREEN (-8125 3100);
DISPLAY INVISIBLE (-8125 3100);
FORCEPROP 1 LAST OFFPAGE TRUE
J 0
(-7900 3050);
DISPLAY 0.872340 (-7900 3050);
PAINT GREEN (-7900 3050);
DISPLAY INVISIBLE (-7900 3050);
FORCEPROP 2 LAST CDS_LIB mstr_standard
J 0
(-8225 3175);
DISPLAY INVISIBLE (-8225 3175);
FORCEADD TAP..1
(-6125 3675);
FORCEPROP 3 LASTPIN (-6175 3675) SIG_NAME M_F_CPU1_SB_DQ<27>
J 0
(-6165 3685);
DISPLAY 0.659574 (-6165 3685);
PAINT MONO (-6165 3685);
DISPLAY INVISIBLE (-6165 3685);
FORCEPROP 1 LASTPIN (-6175 3675) BN 27
J 0
(-6187 3683);
DISPLAY 0.489362 (-6187 3683);
PAINT GREEN (-6187 3683);
FORCEPROP 2 LAST CDS_LIB mstr_standard
J 0
(-6125 3675);
DISPLAY 0.723404 (-6125 3675);
PAINT MONO (-6125 3675);
DISPLAY INVISIBLE (-6125 3675);
FORCEPROP 1 LAST BODY_TYPE PLUMBING
J 0
(-6125 3725);
DISPLAY 0.872340 (-6125 3725);
PAINT GREEN (-6125 3725);
DISPLAY INVISIBLE (-6125 3725);
FORCEPROP 1 LAST HDL_TAP TRUE
J 0
(-5800 3550);
DISPLAY 0.872340 (-5800 3550);
DISPLAY INVISIBLE (-5800 3550);
FORCEPROP 1 LAST PATH I60
J 0
(-6127 3675);
DISPLAY 0.872340 (-6127 3675);
PAINT GREEN (-6127 3675);
DISPLAY INVISIBLE (-6127 3675);
FORCEADD TAP..1
(-6125 3625);
FORCEPROP 3 LASTPIN (-6175 3625) SIG_NAME M_F_CPU1_SB_DQ<26>
J 0
(-6165 3635);
DISPLAY 0.659574 (-6165 3635);
PAINT MONO (-6165 3635);
DISPLAY INVISIBLE (-6165 3635);
FORCEPROP 1 LASTPIN (-6175 3625) BN 26
J 0
(-6187 3633);
DISPLAY 0.489362 (-6187 3633);
PAINT GREEN (-6187 3633);
FORCEPROP 2 LAST CDS_LIB mstr_standard
J 0
(-6125 3625);
DISPLAY 0.723404 (-6125 3625);
PAINT MONO (-6125 3625);
DISPLAY INVISIBLE (-6125 3625);
FORCEPROP 1 LAST BODY_TYPE PLUMBING
J 0
(-6125 3675);
DISPLAY 0.872340 (-6125 3675);
PAINT GREEN (-6125 3675);
DISPLAY INVISIBLE (-6125 3675);
FORCEPROP 1 LAST HDL_TAP TRUE
J 0
(-5800 3500);
DISPLAY 0.872340 (-5800 3500);
DISPLAY INVISIBLE (-5800 3500);
FORCEPROP 1 LAST PATH I61
J 0
(-6127 3625);
DISPLAY 0.872340 (-6127 3625);
PAINT GREEN (-6127 3625);
DISPLAY INVISIBLE (-6127 3625);
FORCEADD TAP..1
(-6125 3475);
FORCEPROP 3 LASTPIN (-6175 3475) SIG_NAME M_F_CPU1_SB_DQ<23>
J 0
(-6165 3485);
DISPLAY 0.659574 (-6165 3485);
PAINT MONO (-6165 3485);
DISPLAY INVISIBLE (-6165 3485);
FORCEPROP 1 LASTPIN (-6175 3475) BN 23
J 0
(-6187 3483);
DISPLAY 0.489362 (-6187 3483);
PAINT GREEN (-6187 3483);
FORCEPROP 2 LAST CDS_LIB mstr_standard
J 0
(-6125 3475);
DISPLAY 0.723404 (-6125 3475);
PAINT MONO (-6125 3475);
DISPLAY INVISIBLE (-6125 3475);
FORCEPROP 1 LAST BODY_TYPE PLUMBING
J 0
(-6125 3525);
DISPLAY 0.872340 (-6125 3525);
PAINT GREEN (-6125 3525);
DISPLAY INVISIBLE (-6125 3525);
FORCEPROP 1 LAST HDL_TAP TRUE
J 0
(-5800 3350);
DISPLAY 0.872340 (-5800 3350);
DISPLAY INVISIBLE (-5800 3350);
FORCEPROP 1 LAST PATH I62
J 0
(-6127 3475);
DISPLAY 0.872340 (-6127 3475);
PAINT GREEN (-6127 3475);
DISPLAY INVISIBLE (-6127 3475);
FORCEADD TAP..1
(-6125 3775);
FORCEPROP 3 LASTPIN (-6175 3775) SIG_NAME M_F_CPU1_SB_DQ<29>
J 0
(-6165 3785);
DISPLAY 0.659574 (-6165 3785);
PAINT MONO (-6165 3785);
DISPLAY INVISIBLE (-6165 3785);
FORCEPROP 1 LASTPIN (-6175 3775) BN 29
J 0
(-6187 3783);
DISPLAY 0.489362 (-6187 3783);
PAINT GREEN (-6187 3783);
FORCEPROP 2 LAST CDS_LIB mstr_standard
J 0
(-6125 3775);
DISPLAY 0.723404 (-6125 3775);
PAINT MONO (-6125 3775);
DISPLAY INVISIBLE (-6125 3775);
FORCEPROP 1 LAST BODY_TYPE PLUMBING
J 0
(-6125 3825);
DISPLAY 0.872340 (-6125 3825);
PAINT GREEN (-6125 3825);
DISPLAY INVISIBLE (-6125 3825);
FORCEPROP 1 LAST HDL_TAP TRUE
J 0
(-5800 3650);
DISPLAY 0.872340 (-5800 3650);
DISPLAY INVISIBLE (-5800 3650);
FORCEPROP 1 LAST PATH I63
J 0
(-6127 3775);
DISPLAY 0.872340 (-6127 3775);
PAINT GREEN (-6127 3775);
DISPLAY INVISIBLE (-6127 3775);
FORCEADD TAP..1
(-6125 3875);
FORCEPROP 3 LASTPIN (-6175 3875) SIG_NAME M_F_CPU1_SB_DQ<31>
J 0
(-6165 3885);
DISPLAY 0.659574 (-6165 3885);
PAINT MONO (-6165 3885);
DISPLAY INVISIBLE (-6165 3885);
FORCEPROP 1 LASTPIN (-6175 3875) BN 31
J 0
(-6187 3883);
DISPLAY 0.489362 (-6187 3883);
PAINT GREEN (-6187 3883);
FORCEPROP 2 LAST CDS_LIB mstr_standard
J 0
(-6125 3875);
DISPLAY 0.723404 (-6125 3875);
PAINT MONO (-6125 3875);
DISPLAY INVISIBLE (-6125 3875);
FORCEPROP 1 LAST BODY_TYPE PLUMBING
J 0
(-6125 3925);
DISPLAY 0.872340 (-6125 3925);
PAINT GREEN (-6125 3925);
DISPLAY INVISIBLE (-6125 3925);
FORCEPROP 1 LAST HDL_TAP TRUE
J 0
(-5800 3750);
DISPLAY 0.872340 (-5800 3750);
DISPLAY INVISIBLE (-5800 3750);
FORCEPROP 1 LAST PATH I64
J 0
(-6127 3875);
DISPLAY 0.872340 (-6127 3875);
PAINT GREEN (-6127 3875);
DISPLAY INVISIBLE (-6127 3875);
FORCEADD TAP..1
(-6125 3825);
FORCEPROP 3 LASTPIN (-6175 3825) SIG_NAME M_F_CPU1_SB_DQ<30>
J 0
(-6165 3835);
DISPLAY 0.659574 (-6165 3835);
PAINT MONO (-6165 3835);
DISPLAY INVISIBLE (-6165 3835);
FORCEPROP 1 LASTPIN (-6175 3825) BN 30
J 0
(-6187 3833);
DISPLAY 0.489362 (-6187 3833);
PAINT GREEN (-6187 3833);
FORCEPROP 2 LAST CDS_LIB mstr_standard
J 0
(-6125 3825);
DISPLAY 0.723404 (-6125 3825);
PAINT MONO (-6125 3825);
DISPLAY INVISIBLE (-6125 3825);
FORCEPROP 1 LAST BODY_TYPE PLUMBING
J 0
(-6125 3875);
DISPLAY 0.872340 (-6125 3875);
PAINT GREEN (-6125 3875);
DISPLAY INVISIBLE (-6125 3875);
FORCEPROP 1 LAST HDL_TAP TRUE
J 0
(-5800 3700);
DISPLAY 0.872340 (-5800 3700);
DISPLAY INVISIBLE (-5800 3700);
FORCEPROP 1 LAST PATH I65
J 0
(-6127 3825);
DISPLAY 0.872340 (-6127 3825);
PAINT GREEN (-6127 3825);
DISPLAY INVISIBLE (-6127 3825);
FORCEADD TAP..1
(-6125 3725);
FORCEPROP 3 LASTPIN (-6175 3725) SIG_NAME M_F_CPU1_SB_DQ<28>
J 0
(-6165 3735);
DISPLAY 0.659574 (-6165 3735);
PAINT MONO (-6165 3735);
DISPLAY INVISIBLE (-6165 3735);
FORCEPROP 1 LASTPIN (-6175 3725) BN 28
J 0
(-6187 3733);
DISPLAY 0.489362 (-6187 3733);
PAINT GREEN (-6187 3733);
FORCEPROP 2 LAST CDS_LIB mstr_standard
J 0
(-6125 3725);
DISPLAY 0.723404 (-6125 3725);
PAINT MONO (-6125 3725);
DISPLAY INVISIBLE (-6125 3725);
FORCEPROP 1 LAST BODY_TYPE PLUMBING
J 0
(-6125 3775);
DISPLAY 0.872340 (-6125 3775);
PAINT GREEN (-6125 3775);
DISPLAY INVISIBLE (-6125 3775);
FORCEPROP 1 LAST HDL_TAP TRUE
J 0
(-5800 3600);
DISPLAY 0.872340 (-5800 3600);
DISPLAY INVISIBLE (-5800 3600);
FORCEPROP 1 LAST PATH I66
J 0
(-6127 3725);
DISPLAY 0.872340 (-6127 3725);
PAINT GREEN (-6127 3725);
DISPLAY INVISIBLE (-6127 3725);
FORCEADD OFFPAGE..3
(-5375 3925);
FORCEPROP 2 LAST $XR0 42 
J 0
(-5161 3925);
DISPLAY 0.638298 (-5161 3925);
PAINT MONO (-5161 3925);
FORCEPROP 2 LAST PATH I73
J 0
(-5150 3975);
DISPLAY 1.021277 (-5150 3975);
DISPLAY INVISIBLE (-5150 3975);
FORCEPROP 1 LAST COMMENT_BODY TRUE
J 0
(-5425 3825);
DISPLAY 0.872340 (-5425 3825);
PAINT GREEN (-5425 3825);
DISPLAY INVISIBLE (-5425 3825);
FORCEPROP 1 LAST OFFPAGE TRUE
J 0
(-5050 3800);
DISPLAY 0.872340 (-5050 3800);
PAINT GREEN (-5050 3800);
DISPLAY INVISIBLE (-5050 3800);
FORCEPROP 2 LAST CDS_LIB mstr_standard
J 0
(-5375 3925);
DISPLAY 0.723404 (-5375 3925);
PAINT MONO (-5375 3925);
DISPLAY INVISIBLE (-5375 3925);
FORCEADD TAP..1
R 2
(-7825 3975);
FORCEPROP 3 LASTPIN (-7775 3975) SIG_NAME M_F_CPU1_SA_CB<4>
J 0
(-7765 3985);
DISPLAY 0.659574 (-7765 3985);
PAINT MONO (-7765 3985);
DISPLAY INVISIBLE (-7765 3985);
FORCEPROP 1 LASTPIN (-7775 3975) BN 4
J 2
(-7763 3983);
DISPLAY 0.489362 (-7763 3983);
PAINT GREEN (-7763 3983);
FORCEPROP 2 LAST CDS_LIB mstr_standard
J 0
(-7825 3975);
DISPLAY 0.723404 (-7825 3975);
PAINT MONO (-7825 3975);
DISPLAY INVISIBLE (-7825 3975);
FORCEPROP 1 LAST BODY_TYPE PLUMBING
J 2
(-7825 4025);
DISPLAY 0.872340 (-7825 4025);
PAINT GREEN (-7825 4025);
DISPLAY INVISIBLE (-7825 4025);
FORCEPROP 1 LAST HDL_TAP TRUE
J 2
(-8150 3850);
DISPLAY 0.872340 (-8150 3850);
DISPLAY INVISIBLE (-8150 3850);
FORCEPROP 1 LAST PATH I76
J 2
(-7823 3975);
DISPLAY 0.872340 (-7823 3975);
PAINT GREEN (-7823 3975);
DISPLAY INVISIBLE (-7823 3975);
FORCEADD TAP..1
R 2
(-7825 4025);
FORCEPROP 3 LASTPIN (-7775 4025) SIG_NAME M_F_CPU1_SA_CB<5>
J 0
(-7765 4035);
DISPLAY 0.659574 (-7765 4035);
PAINT MONO (-7765 4035);
DISPLAY INVISIBLE (-7765 4035);
FORCEPROP 1 LASTPIN (-7775 4025) BN 5
J 2
(-7763 4033);
DISPLAY 0.489362 (-7763 4033);
PAINT GREEN (-7763 4033);
FORCEPROP 2 LAST CDS_LIB mstr_standard
J 0
(-7825 4025);
DISPLAY 0.723404 (-7825 4025);
PAINT MONO (-7825 4025);
DISPLAY INVISIBLE (-7825 4025);
FORCEPROP 1 LAST BODY_TYPE PLUMBING
J 2
(-7825 4075);
DISPLAY 0.872340 (-7825 4075);
PAINT GREEN (-7825 4075);
DISPLAY INVISIBLE (-7825 4075);
FORCEPROP 1 LAST HDL_TAP TRUE
J 2
(-8150 3900);
DISPLAY 0.872340 (-8150 3900);
DISPLAY INVISIBLE (-8150 3900);
FORCEPROP 1 LAST PATH I77
J 2
(-7823 4025);
DISPLAY 0.872340 (-7823 4025);
PAINT GREEN (-7823 4025);
DISPLAY INVISIBLE (-7823 4025);
FORCEADD TAP..1
R 2
(-7825 4125);
FORCEPROP 3 LASTPIN (-7775 4125) SIG_NAME M_F_CPU1_SA_CB<7>
J 0
(-7765 4135);
DISPLAY 0.659574 (-7765 4135);
PAINT MONO (-7765 4135);
DISPLAY INVISIBLE (-7765 4135);
FORCEPROP 1 LASTPIN (-7775 4125) BN 7
J 2
(-7763 4133);
DISPLAY 0.489362 (-7763 4133);
PAINT GREEN (-7763 4133);
FORCEPROP 2 LAST CDS_LIB mstr_standard
J 0
(-7825 4125);
DISPLAY 0.723404 (-7825 4125);
PAINT MONO (-7825 4125);
DISPLAY INVISIBLE (-7825 4125);
FORCEPROP 1 LAST BODY_TYPE PLUMBING
J 2
(-7825 4175);
DISPLAY 0.872340 (-7825 4175);
PAINT GREEN (-7825 4175);
DISPLAY INVISIBLE (-7825 4175);
FORCEPROP 1 LAST HDL_TAP TRUE
J 2
(-8150 4000);
DISPLAY 0.872340 (-8150 4000);
DISPLAY INVISIBLE (-8150 4000);
FORCEPROP 1 LAST PATH I78
J 2
(-7823 4125);
DISPLAY 0.872340 (-7823 4125);
PAINT GREEN (-7823 4125);
DISPLAY INVISIBLE (-7823 4125);
FORCEADD TAP..1
R 2
(-7825 4075);
FORCEPROP 3 LASTPIN (-7775 4075) SIG_NAME M_F_CPU1_SA_CB<6>
J 0
(-7765 4085);
DISPLAY 0.659574 (-7765 4085);
PAINT MONO (-7765 4085);
DISPLAY INVISIBLE (-7765 4085);
FORCEPROP 1 LASTPIN (-7775 4075) BN 6
J 2
(-7763 4083);
DISPLAY 0.489362 (-7763 4083);
PAINT GREEN (-7763 4083);
FORCEPROP 2 LAST CDS_LIB mstr_standard
J 0
(-7825 4075);
DISPLAY 0.723404 (-7825 4075);
PAINT MONO (-7825 4075);
DISPLAY INVISIBLE (-7825 4075);
FORCEPROP 1 LAST BODY_TYPE PLUMBING
J 2
(-7825 4125);
DISPLAY 0.872340 (-7825 4125);
PAINT GREEN (-7825 4125);
DISPLAY INVISIBLE (-7825 4125);
FORCEPROP 1 LAST HDL_TAP TRUE
J 2
(-8150 3950);
DISPLAY 0.872340 (-8150 3950);
DISPLAY INVISIBLE (-8150 3950);
FORCEPROP 1 LAST PATH I79
J 2
(-7823 4075);
DISPLAY 0.872340 (-7823 4075);
PAINT GREEN (-7823 4075);
DISPLAY INVISIBLE (-7823 4075);
FORCEADD OFFPAGE..1
(-8425 3025);
FORCEPROP 2 LAST $XR0 102 
J 0
(-8677 3025);
DISPLAY 0.638298 (-8677 3025);
PAINT MONO (-8677 3025);
FORCEPROP 2 LAST PATH I8
J 0
(-8675 3075);
DISPLAY 1.021277 (-8675 3075);
DISPLAY INVISIBLE (-8675 3075);
FORCEPROP 1 LAST COMMENT_BODY TRUE
J 0
(-8300 2925);
DISPLAY 0.872340 (-8300 2925);
PAINT GREEN (-8300 2925);
DISPLAY INVISIBLE (-8300 2925);
FORCEPROP 1 LAST OFFPAGE TRUE
J 0
(-8100 2900);
DISPLAY 0.872340 (-8100 2900);
PAINT GREEN (-8100 2900);
DISPLAY INVISIBLE (-8100 2900);
FORCEPROP 2 LAST CDS_LIB mstr_standard
J 0
(-8425 3025);
DISPLAY 0.808511 (-8425 3025);
DISPLAY INVISIBLE (-8425 3025);
FORCEADD TAP..1
R 2
(-7825 4825);
FORCEPROP 3 LASTPIN (-7775 4825) SIG_NAME M_F_CPU1_SB_CA<0>
J 0
(-7765 4835);
DISPLAY 0.659574 (-7765 4835);
PAINT MONO (-7765 4835);
DISPLAY INVISIBLE (-7765 4835);
FORCEPROP 1 LASTPIN (-7775 4825) BN 0
J 2
(-7763 4833);
DISPLAY 0.489362 (-7763 4833);
PAINT GREEN (-7763 4833);
FORCEPROP 2 LAST CDS_LIB mstr_standard
J 0
(-7825 4825);
DISPLAY 0.723404 (-7825 4825);
PAINT MONO (-7825 4825);
DISPLAY INVISIBLE (-7825 4825);
FORCEPROP 1 LAST BODY_TYPE PLUMBING
J 2
(-7825 4875);
DISPLAY 0.872340 (-7825 4875);
PAINT GREEN (-7825 4875);
DISPLAY INVISIBLE (-7825 4875);
FORCEPROP 1 LAST HDL_TAP TRUE
J 2
(-8150 4700);
DISPLAY 0.872340 (-8150 4700);
DISPLAY INVISIBLE (-8150 4700);
FORCEPROP 1 LAST PATH I80
J 2
(-7823 4825);
DISPLAY 0.872340 (-7823 4825);
PAINT GREEN (-7823 4825);
DISPLAY INVISIBLE (-7823 4825);
FORCEADD TAP..1
R 2
(-7825 4875);
FORCEPROP 3 LASTPIN (-7775 4875) SIG_NAME M_F_CPU1_SB_CA<1>
J 0
(-7765 4885);
DISPLAY 0.659574 (-7765 4885);
PAINT MONO (-7765 4885);
DISPLAY INVISIBLE (-7765 4885);
FORCEPROP 1 LASTPIN (-7775 4875) BN 1
J 2
(-7763 4883);
DISPLAY 0.489362 (-7763 4883);
PAINT GREEN (-7763 4883);
FORCEPROP 2 LAST CDS_LIB mstr_standard
J 0
(-7825 4875);
DISPLAY 0.723404 (-7825 4875);
PAINT MONO (-7825 4875);
DISPLAY INVISIBLE (-7825 4875);
FORCEPROP 1 LAST BODY_TYPE PLUMBING
J 2
(-7825 4925);
DISPLAY 0.872340 (-7825 4925);
PAINT GREEN (-7825 4925);
DISPLAY INVISIBLE (-7825 4925);
FORCEPROP 1 LAST HDL_TAP TRUE
J 2
(-8150 4750);
DISPLAY 0.872340 (-8150 4750);
DISPLAY INVISIBLE (-8150 4750);
FORCEPROP 1 LAST PATH I81
J 2
(-7823 4875);
DISPLAY 0.872340 (-7823 4875);
PAINT GREEN (-7823 4875);
DISPLAY INVISIBLE (-7823 4875);
FORCEADD TAP..1
R 2
(-7825 4925);
FORCEPROP 3 LASTPIN (-7775 4925) SIG_NAME M_F_CPU1_SB_CA<2>
J 0
(-7765 4935);
DISPLAY 0.659574 (-7765 4935);
PAINT MONO (-7765 4935);
DISPLAY INVISIBLE (-7765 4935);
FORCEPROP 1 LASTPIN (-7775 4925) BN 2
J 2
(-7763 4933);
DISPLAY 0.489362 (-7763 4933);
PAINT GREEN (-7763 4933);
FORCEPROP 2 LAST CDS_LIB mstr_standard
J 0
(-7825 4925);
DISPLAY 0.723404 (-7825 4925);
PAINT MONO (-7825 4925);
DISPLAY INVISIBLE (-7825 4925);
FORCEPROP 1 LAST BODY_TYPE PLUMBING
J 2
(-7825 4975);
DISPLAY 0.872340 (-7825 4975);
PAINT GREEN (-7825 4975);
DISPLAY INVISIBLE (-7825 4975);
FORCEPROP 1 LAST HDL_TAP TRUE
J 2
(-8150 4800);
DISPLAY 0.872340 (-8150 4800);
DISPLAY INVISIBLE (-8150 4800);
FORCEPROP 1 LAST PATH I82
J 2
(-7823 4925);
DISPLAY 0.872340 (-7823 4925);
PAINT GREEN (-7823 4925);
DISPLAY INVISIBLE (-7823 4925);
FORCEADD TAP..1
R 2
(-7825 5025);
FORCEPROP 3 LASTPIN (-7775 5025) SIG_NAME M_F_CPU1_SB_CA<4>
J 0
(-7765 5035);
DISPLAY 0.659574 (-7765 5035);
PAINT MONO (-7765 5035);
DISPLAY INVISIBLE (-7765 5035);
FORCEPROP 1 LASTPIN (-7775 5025) BN 4
J 2
(-7763 5033);
DISPLAY 0.489362 (-7763 5033);
PAINT GREEN (-7763 5033);
FORCEPROP 2 LAST CDS_LIB mstr_standard
J 0
(-7825 5025);
DISPLAY 0.723404 (-7825 5025);
PAINT MONO (-7825 5025);
DISPLAY INVISIBLE (-7825 5025);
FORCEPROP 1 LAST BODY_TYPE PLUMBING
J 2
(-7825 5075);
DISPLAY 0.872340 (-7825 5075);
PAINT GREEN (-7825 5075);
DISPLAY INVISIBLE (-7825 5075);
FORCEPROP 1 LAST HDL_TAP TRUE
J 2
(-8150 4900);
DISPLAY 0.872340 (-8150 4900);
DISPLAY INVISIBLE (-8150 4900);
FORCEPROP 1 LAST PATH I83
J 2
(-7823 5025);
DISPLAY 0.872340 (-7823 5025);
PAINT GREEN (-7823 5025);
DISPLAY INVISIBLE (-7823 5025);
FORCEADD TAP..1
R 2
(-7825 4975);
FORCEPROP 3 LASTPIN (-7775 4975) SIG_NAME M_F_CPU1_SB_CA<3>
J 0
(-7765 4985);
DISPLAY 0.659574 (-7765 4985);
PAINT MONO (-7765 4985);
DISPLAY INVISIBLE (-7765 4985);
FORCEPROP 1 LASTPIN (-7775 4975) BN 3
J 2
(-7763 4983);
DISPLAY 0.489362 (-7763 4983);
PAINT GREEN (-7763 4983);
FORCEPROP 2 LAST CDS_LIB mstr_standard
J 0
(-7825 4975);
DISPLAY 0.723404 (-7825 4975);
PAINT MONO (-7825 4975);
DISPLAY INVISIBLE (-7825 4975);
FORCEPROP 1 LAST BODY_TYPE PLUMBING
J 2
(-7825 5025);
DISPLAY 0.872340 (-7825 5025);
PAINT GREEN (-7825 5025);
DISPLAY INVISIBLE (-7825 5025);
FORCEPROP 1 LAST HDL_TAP TRUE
J 2
(-8150 4850);
DISPLAY 0.872340 (-8150 4850);
DISPLAY INVISIBLE (-8150 4850);
FORCEPROP 1 LAST PATH I84
J 2
(-7823 4975);
DISPLAY 0.872340 (-7823 4975);
PAINT GREEN (-7823 4975);
DISPLAY INVISIBLE (-7823 4975);
FORCEADD TAP..1
R 2
(-7825 5075);
FORCEPROP 3 LASTPIN (-7775 5075) SIG_NAME M_F_CPU1_SB_CA<5>
J 0
(-7765 5085);
DISPLAY 0.659574 (-7765 5085);
PAINT MONO (-7765 5085);
DISPLAY INVISIBLE (-7765 5085);
FORCEPROP 1 LASTPIN (-7775 5075) BN 5
J 2
(-7763 5083);
DISPLAY 0.489362 (-7763 5083);
PAINT GREEN (-7763 5083);
FORCEPROP 2 LAST CDS_LIB mstr_standard
J 0
(-7825 5075);
DISPLAY 0.723404 (-7825 5075);
PAINT MONO (-7825 5075);
DISPLAY INVISIBLE (-7825 5075);
FORCEPROP 1 LAST BODY_TYPE PLUMBING
J 2
(-7825 5125);
DISPLAY 0.872340 (-7825 5125);
PAINT GREEN (-7825 5125);
DISPLAY INVISIBLE (-7825 5125);
FORCEPROP 1 LAST HDL_TAP TRUE
J 2
(-8150 4950);
DISPLAY 0.872340 (-8150 4950);
DISPLAY INVISIBLE (-8150 4950);
FORCEPROP 1 LAST PATH I85
J 2
(-7823 5075);
DISPLAY 0.872340 (-7823 5075);
PAINT GREEN (-7823 5075);
DISPLAY INVISIBLE (-7823 5075);
FORCEADD TAP..1
R 2
(-7825 5125);
FORCEPROP 3 LASTPIN (-7775 5125) SIG_NAME M_F_CPU1_SB_CA<6>
J 0
(-7765 5135);
DISPLAY 0.659574 (-7765 5135);
PAINT MONO (-7765 5135);
DISPLAY INVISIBLE (-7765 5135);
FORCEPROP 1 LASTPIN (-7775 5125) BN 6
J 2
(-7763 5133);
DISPLAY 0.489362 (-7763 5133);
PAINT GREEN (-7763 5133);
FORCEPROP 2 LAST CDS_LIB mstr_standard
J 0
(-7825 5125);
DISPLAY 0.723404 (-7825 5125);
PAINT MONO (-7825 5125);
DISPLAY INVISIBLE (-7825 5125);
FORCEPROP 1 LAST BODY_TYPE PLUMBING
J 2
(-7825 5175);
DISPLAY 0.872340 (-7825 5175);
PAINT GREEN (-7825 5175);
DISPLAY INVISIBLE (-7825 5175);
FORCEPROP 1 LAST HDL_TAP TRUE
J 2
(-8150 5000);
DISPLAY 0.872340 (-8150 5000);
DISPLAY INVISIBLE (-8150 5000);
FORCEPROP 1 LAST PATH I86
J 2
(-7823 5125);
DISPLAY 0.872340 (-7823 5125);
PAINT GREEN (-7823 5125);
DISPLAY INVISIBLE (-7823 5125);
FORCEADD TAP..1
R 2
(-7825 5225);
FORCEPROP 3 LASTPIN (-7775 5225) SIG_NAME M_F_CPU1_SA_CA<0>
J 0
(-7765 5235);
DISPLAY 0.659574 (-7765 5235);
PAINT MONO (-7765 5235);
DISPLAY INVISIBLE (-7765 5235);
FORCEPROP 1 LASTPIN (-7775 5225) BN 0
J 2
(-7763 5233);
DISPLAY 0.489362 (-7763 5233);
PAINT GREEN (-7763 5233);
FORCEPROP 2 LAST CDS_LIB mstr_standard
J 0
(-7825 5225);
DISPLAY 0.723404 (-7825 5225);
PAINT MONO (-7825 5225);
DISPLAY INVISIBLE (-7825 5225);
FORCEPROP 1 LAST BODY_TYPE PLUMBING
J 2
(-7825 5275);
DISPLAY 0.872340 (-7825 5275);
PAINT GREEN (-7825 5275);
DISPLAY INVISIBLE (-7825 5275);
FORCEPROP 1 LAST HDL_TAP TRUE
J 2
(-8150 5100);
DISPLAY 0.872340 (-8150 5100);
DISPLAY INVISIBLE (-8150 5100);
FORCEPROP 1 LAST PATH I87
J 2
(-7823 5225);
DISPLAY 0.872340 (-7823 5225);
PAINT GREEN (-7823 5225);
DISPLAY INVISIBLE (-7823 5225);
FORCEADD TAP..1
R 2
(-7825 5275);
FORCEPROP 3 LASTPIN (-7775 5275) SIG_NAME M_F_CPU1_SA_CA<1>
J 0
(-7765 5285);
DISPLAY 0.659574 (-7765 5285);
PAINT MONO (-7765 5285);
DISPLAY INVISIBLE (-7765 5285);
FORCEPROP 1 LASTPIN (-7775 5275) BN 1
J 2
(-7763 5283);
DISPLAY 0.489362 (-7763 5283);
PAINT GREEN (-7763 5283);
FORCEPROP 2 LAST CDS_LIB mstr_standard
J 0
(-7825 5275);
DISPLAY 0.723404 (-7825 5275);
PAINT MONO (-7825 5275);
DISPLAY INVISIBLE (-7825 5275);
FORCEPROP 1 LAST BODY_TYPE PLUMBING
J 2
(-7825 5325);
DISPLAY 0.872340 (-7825 5325);
PAINT GREEN (-7825 5325);
DISPLAY INVISIBLE (-7825 5325);
FORCEPROP 1 LAST HDL_TAP TRUE
J 2
(-8150 5150);
DISPLAY 0.872340 (-8150 5150);
DISPLAY INVISIBLE (-8150 5150);
FORCEPROP 1 LAST PATH I88
J 2
(-7823 5275);
DISPLAY 0.872340 (-7823 5275);
PAINT GREEN (-7823 5275);
DISPLAY INVISIBLE (-7823 5275);
FORCEADD TAP..1
R 2
(-7825 5325);
FORCEPROP 3 LASTPIN (-7775 5325) SIG_NAME M_F_CPU1_SA_CA<2>
J 0
(-7765 5335);
DISPLAY 0.659574 (-7765 5335);
PAINT MONO (-7765 5335);
DISPLAY INVISIBLE (-7765 5335);
FORCEPROP 1 LASTPIN (-7775 5325) BN 2
J 2
(-7763 5333);
DISPLAY 0.489362 (-7763 5333);
PAINT GREEN (-7763 5333);
FORCEPROP 2 LAST CDS_LIB mstr_standard
J 0
(-7825 5325);
DISPLAY 0.723404 (-7825 5325);
PAINT MONO (-7825 5325);
DISPLAY INVISIBLE (-7825 5325);
FORCEPROP 1 LAST BODY_TYPE PLUMBING
J 2
(-7825 5375);
DISPLAY 0.872340 (-7825 5375);
PAINT GREEN (-7825 5375);
DISPLAY INVISIBLE (-7825 5375);
FORCEPROP 1 LAST HDL_TAP TRUE
J 2
(-8150 5200);
DISPLAY 0.872340 (-8150 5200);
DISPLAY INVISIBLE (-8150 5200);
FORCEPROP 1 LAST PATH I89
J 2
(-7823 5325);
DISPLAY 0.872340 (-7823 5325);
PAINT GREEN (-7823 5325);
DISPLAY INVISIBLE (-7823 5325);
FORCEADD OFFPAGE..1
(-8225 3225);
FORCEPROP 2 LAST $XR0 42 
J 0
(-8476 3225);
DISPLAY 0.638298 (-8476 3225);
PAINT MONO (-8476 3225);
FORCEPROP 2 LAST PATH I9
J 0
(-8425 3275);
DISPLAY 1.021277 (-8425 3275);
DISPLAY INVISIBLE (-8425 3275);
FORCEPROP 1 LAST COMMENT_BODY TRUE
J 0
(-8100 3125);
DISPLAY 0.872340 (-8100 3125);
PAINT GREEN (-8100 3125);
DISPLAY INVISIBLE (-8100 3125);
FORCEPROP 1 LAST OFFPAGE TRUE
J 0
(-7900 3100);
DISPLAY 0.872340 (-7900 3100);
PAINT GREEN (-7900 3100);
DISPLAY INVISIBLE (-7900 3100);
FORCEPROP 2 LAST CDS_LIB mstr_standard
J 0
(-8225 3225);
DISPLAY 0.808511 (-8225 3225);
DISPLAY INVISIBLE (-8225 3225);
FORCEADD TAP..1
R 2
(-7825 5375);
FORCEPROP 3 LASTPIN (-7775 5375) SIG_NAME M_F_CPU1_SA_CA<3>
J 0
(-7765 5385);
DISPLAY 0.659574 (-7765 5385);
PAINT MONO (-7765 5385);
DISPLAY INVISIBLE (-7765 5385);
FORCEPROP 1 LASTPIN (-7775 5375) BN 3
J 2
(-7763 5383);
DISPLAY 0.489362 (-7763 5383);
PAINT GREEN (-7763 5383);
FORCEPROP 2 LAST CDS_LIB mstr_standard
J 0
(-7825 5375);
DISPLAY 0.723404 (-7825 5375);
PAINT MONO (-7825 5375);
DISPLAY INVISIBLE (-7825 5375);
FORCEPROP 1 LAST BODY_TYPE PLUMBING
J 2
(-7825 5425);
DISPLAY 0.872340 (-7825 5425);
PAINT GREEN (-7825 5425);
DISPLAY INVISIBLE (-7825 5425);
FORCEPROP 1 LAST HDL_TAP TRUE
J 2
(-8150 5250);
DISPLAY 0.872340 (-8150 5250);
DISPLAY INVISIBLE (-8150 5250);
FORCEPROP 1 LAST PATH I90
J 2
(-7823 5375);
DISPLAY 0.872340 (-7823 5375);
PAINT GREEN (-7823 5375);
DISPLAY INVISIBLE (-7823 5375);
FORCEADD TAP..1
R 2
(-7825 5425);
FORCEPROP 3 LASTPIN (-7775 5425) SIG_NAME M_F_CPU1_SA_CA<4>
J 0
(-7765 5435);
DISPLAY 0.659574 (-7765 5435);
PAINT MONO (-7765 5435);
DISPLAY INVISIBLE (-7765 5435);
FORCEPROP 1 LASTPIN (-7775 5425) BN 4
J 2
(-7763 5433);
DISPLAY 0.489362 (-7763 5433);
PAINT GREEN (-7763 5433);
FORCEPROP 2 LAST CDS_LIB mstr_standard
J 0
(-7825 5425);
DISPLAY 0.723404 (-7825 5425);
PAINT MONO (-7825 5425);
DISPLAY INVISIBLE (-7825 5425);
FORCEPROP 1 LAST BODY_TYPE PLUMBING
J 2
(-7825 5475);
DISPLAY 0.872340 (-7825 5475);
PAINT GREEN (-7825 5475);
DISPLAY INVISIBLE (-7825 5475);
FORCEPROP 1 LAST HDL_TAP TRUE
J 2
(-8150 5300);
DISPLAY 0.872340 (-8150 5300);
DISPLAY INVISIBLE (-8150 5300);
FORCEPROP 1 LAST PATH I91
J 2
(-7823 5425);
DISPLAY 0.872340 (-7823 5425);
PAINT GREEN (-7823 5425);
DISPLAY INVISIBLE (-7823 5425);
FORCEADD TAP..1
R 2
(-7825 5475);
FORCEPROP 3 LASTPIN (-7775 5475) SIG_NAME M_F_CPU1_SA_CA<5>
J 0
(-7765 5485);
DISPLAY 0.659574 (-7765 5485);
PAINT MONO (-7765 5485);
DISPLAY INVISIBLE (-7765 5485);
FORCEPROP 1 LASTPIN (-7775 5475) BN 5
J 2
(-7763 5483);
DISPLAY 0.489362 (-7763 5483);
PAINT GREEN (-7763 5483);
FORCEPROP 2 LAST CDS_LIB mstr_standard
J 0
(-7825 5475);
DISPLAY 0.723404 (-7825 5475);
PAINT MONO (-7825 5475);
DISPLAY INVISIBLE (-7825 5475);
FORCEPROP 1 LAST BODY_TYPE PLUMBING
J 2
(-7825 5525);
DISPLAY 0.872340 (-7825 5525);
PAINT GREEN (-7825 5525);
DISPLAY INVISIBLE (-7825 5525);
FORCEPROP 1 LAST HDL_TAP TRUE
J 2
(-8150 5350);
DISPLAY 0.872340 (-8150 5350);
DISPLAY INVISIBLE (-8150 5350);
FORCEPROP 1 LAST PATH I92
J 2
(-7823 5475);
DISPLAY 0.872340 (-7823 5475);
PAINT GREEN (-7823 5475);
DISPLAY INVISIBLE (-7823 5475);
FORCEADD TAP..1
R 2
(-7825 5525);
FORCEPROP 3 LASTPIN (-7775 5525) SIG_NAME M_F_CPU1_SA_CA<6>
J 0
(-7765 5535);
DISPLAY 0.659574 (-7765 5535);
PAINT MONO (-7765 5535);
DISPLAY INVISIBLE (-7765 5535);
FORCEPROP 1 LASTPIN (-7775 5525) BN 6
J 2
(-7763 5533);
DISPLAY 0.489362 (-7763 5533);
PAINT GREEN (-7763 5533);
FORCEPROP 2 LAST CDS_LIB mstr_standard
J 0
(-7825 5525);
DISPLAY 0.723404 (-7825 5525);
PAINT MONO (-7825 5525);
DISPLAY INVISIBLE (-7825 5525);
FORCEPROP 1 LAST BODY_TYPE PLUMBING
J 2
(-7825 5575);
DISPLAY 0.872340 (-7825 5575);
PAINT GREEN (-7825 5575);
DISPLAY INVISIBLE (-7825 5575);
FORCEPROP 1 LAST HDL_TAP TRUE
J 2
(-8150 5400);
DISPLAY 0.872340 (-8150 5400);
DISPLAY INVISIBLE (-8150 5400);
FORCEPROP 1 LAST PATH I93
J 2
(-7823 5525);
DISPLAY 0.872340 (-7823 5525);
PAINT GREEN (-7823 5525);
DISPLAY INVISIBLE (-7823 5525);
FORCEADD TAP..1
(-6125 3975);
FORCEPROP 3 LASTPIN (-6175 3975) SIG_NAME M_F_CPU1_SA_DQ<0>
J 0
(-6165 3985);
DISPLAY 0.659574 (-6165 3985);
PAINT MONO (-6165 3985);
DISPLAY INVISIBLE (-6165 3985);
FORCEPROP 1 LASTPIN (-6175 3975) BN 0
J 0
(-6187 3983);
DISPLAY 0.489362 (-6187 3983);
PAINT GREEN (-6187 3983);
FORCEPROP 2 LAST CDS_LIB mstr_standard
J 0
(-6125 3975);
DISPLAY 0.723404 (-6125 3975);
PAINT MONO (-6125 3975);
DISPLAY INVISIBLE (-6125 3975);
FORCEPROP 1 LAST BODY_TYPE PLUMBING
J 0
(-6125 4025);
DISPLAY 0.872340 (-6125 4025);
PAINT GREEN (-6125 4025);
DISPLAY INVISIBLE (-6125 4025);
FORCEPROP 1 LAST HDL_TAP TRUE
J 0
(-5800 3850);
DISPLAY 0.872340 (-5800 3850);
DISPLAY INVISIBLE (-5800 3850);
FORCEPROP 1 LAST PATH I94
J 0
(-6127 3975);
DISPLAY 0.872340 (-6127 3975);
PAINT GREEN (-6127 3975);
DISPLAY INVISIBLE (-6127 3975);
FORCEADD TAP..1
(-6125 4025);
FORCEPROP 3 LASTPIN (-6175 4025) SIG_NAME M_F_CPU1_SA_DQ<1>
J 0
(-6165 4035);
DISPLAY 0.659574 (-6165 4035);
PAINT MONO (-6165 4035);
DISPLAY INVISIBLE (-6165 4035);
FORCEPROP 1 LASTPIN (-6175 4025) BN 1
J 0
(-6187 4033);
DISPLAY 0.489362 (-6187 4033);
PAINT GREEN (-6187 4033);
FORCEPROP 2 LAST CDS_LIB mstr_standard
J 0
(-6125 4025);
DISPLAY 0.723404 (-6125 4025);
PAINT MONO (-6125 4025);
DISPLAY INVISIBLE (-6125 4025);
FORCEPROP 1 LAST BODY_TYPE PLUMBING
J 0
(-6125 4075);
DISPLAY 0.872340 (-6125 4075);
PAINT GREEN (-6125 4075);
DISPLAY INVISIBLE (-6125 4075);
FORCEPROP 1 LAST HDL_TAP TRUE
J 0
(-5800 3900);
DISPLAY 0.872340 (-5800 3900);
DISPLAY INVISIBLE (-5800 3900);
FORCEPROP 1 LAST PATH I95
J 0
(-6127 4025);
DISPLAY 0.872340 (-6127 4025);
PAINT GREEN (-6127 4025);
DISPLAY INVISIBLE (-6127 4025);
FORCEADD TAP..1
(-6125 4075);
FORCEPROP 3 LASTPIN (-6175 4075) SIG_NAME M_F_CPU1_SA_DQ<2>
J 0
(-6165 4085);
DISPLAY 0.659574 (-6165 4085);
PAINT MONO (-6165 4085);
DISPLAY INVISIBLE (-6165 4085);
FORCEPROP 1 LASTPIN (-6175 4075) BN 2
J 0
(-6187 4083);
DISPLAY 0.489362 (-6187 4083);
PAINT GREEN (-6187 4083);
FORCEPROP 2 LAST CDS_LIB mstr_standard
J 0
(-6125 4075);
DISPLAY 0.723404 (-6125 4075);
PAINT MONO (-6125 4075);
DISPLAY INVISIBLE (-6125 4075);
FORCEPROP 1 LAST BODY_TYPE PLUMBING
J 0
(-6125 4125);
DISPLAY 0.872340 (-6125 4125);
PAINT GREEN (-6125 4125);
DISPLAY INVISIBLE (-6125 4125);
FORCEPROP 1 LAST HDL_TAP TRUE
J 0
(-5800 3950);
DISPLAY 0.872340 (-5800 3950);
DISPLAY INVISIBLE (-5800 3950);
FORCEPROP 1 LAST PATH I96
J 0
(-6127 4075);
DISPLAY 0.872340 (-6127 4075);
PAINT GREEN (-6127 4075);
DISPLAY INVISIBLE (-6127 4075);
FORCEADD TAP..1
(-6125 4125);
FORCEPROP 3 LASTPIN (-6175 4125) SIG_NAME M_F_CPU1_SA_DQ<3>
J 0
(-6165 4135);
DISPLAY 0.659574 (-6165 4135);
PAINT MONO (-6165 4135);
DISPLAY INVISIBLE (-6165 4135);
FORCEPROP 1 LASTPIN (-6175 4125) BN 3
J 0
(-6187 4133);
DISPLAY 0.489362 (-6187 4133);
PAINT GREEN (-6187 4133);
FORCEPROP 2 LAST CDS_LIB mstr_standard
J 0
(-6125 4125);
DISPLAY 0.723404 (-6125 4125);
PAINT MONO (-6125 4125);
DISPLAY INVISIBLE (-6125 4125);
FORCEPROP 1 LAST BODY_TYPE PLUMBING
J 0
(-6125 4175);
DISPLAY 0.872340 (-6125 4175);
PAINT GREEN (-6125 4175);
DISPLAY INVISIBLE (-6125 4175);
FORCEPROP 1 LAST HDL_TAP TRUE
J 0
(-5800 4000);
DISPLAY 0.872340 (-5800 4000);
DISPLAY INVISIBLE (-5800 4000);
FORCEPROP 1 LAST PATH I97
J 0
(-6127 4125);
DISPLAY 0.872340 (-6127 4125);
PAINT GREEN (-6127 4125);
DISPLAY INVISIBLE (-6127 4125);
FORCEADD TAP..1
(-6125 4175);
FORCEPROP 3 LASTPIN (-6175 4175) SIG_NAME M_F_CPU1_SA_DQ<4>
J 0
(-6165 4185);
DISPLAY 0.659574 (-6165 4185);
PAINT MONO (-6165 4185);
DISPLAY INVISIBLE (-6165 4185);
FORCEPROP 1 LASTPIN (-6175 4175) BN 4
J 0
(-6187 4183);
DISPLAY 0.489362 (-6187 4183);
PAINT GREEN (-6187 4183);
FORCEPROP 2 LAST CDS_LIB mstr_standard
J 0
(-6125 4175);
DISPLAY 0.723404 (-6125 4175);
PAINT MONO (-6125 4175);
DISPLAY INVISIBLE (-6125 4175);
FORCEPROP 1 LAST BODY_TYPE PLUMBING
J 0
(-6125 4225);
DISPLAY 0.872340 (-6125 4225);
PAINT GREEN (-6125 4225);
DISPLAY INVISIBLE (-6125 4225);
FORCEPROP 1 LAST HDL_TAP TRUE
J 0
(-5800 4050);
DISPLAY 0.872340 (-5800 4050);
DISPLAY INVISIBLE (-5800 4050);
FORCEPROP 1 LAST PATH I98
J 0
(-6127 4175);
DISPLAY 0.872340 (-6127 4175);
PAINT GREEN (-6127 4175);
DISPLAY INVISIBLE (-6127 4175);
FORCEADD TAP..1
(-6125 4225);
FORCEPROP 3 LASTPIN (-6175 4225) SIG_NAME M_F_CPU1_SA_DQ<5>
J 0
(-6165 4235);
DISPLAY 0.659574 (-6165 4235);
PAINT MONO (-6165 4235);
DISPLAY INVISIBLE (-6165 4235);
FORCEPROP 1 LASTPIN (-6175 4225) BN 5
J 0
(-6187 4233);
DISPLAY 0.489362 (-6187 4233);
PAINT GREEN (-6187 4233);
FORCEPROP 2 LAST CDS_LIB mstr_standard
J 0
(-6125 4225);
DISPLAY 0.723404 (-6125 4225);
PAINT MONO (-6125 4225);
DISPLAY INVISIBLE (-6125 4225);
FORCEPROP 1 LAST BODY_TYPE PLUMBING
J 0
(-6125 4275);
DISPLAY 0.872340 (-6125 4275);
PAINT GREEN (-6125 4275);
DISPLAY INVISIBLE (-6125 4275);
FORCEPROP 1 LAST HDL_TAP TRUE
J 0
(-5800 4100);
DISPLAY 0.872340 (-5800 4100);
DISPLAY INVISIBLE (-5800 4100);
FORCEPROP 1 LAST PATH I99
J 0
(-6127 4225);
DISPLAY 0.872340 (-6127 4225);
PAINT GREEN (-6127 4225);
DISPLAY INVISIBLE (-6127 4225);
FORCEADD QUANTA_TITLE_BLOCK_C..1
(-100 100);
FORCEPROP 0 LAST CDS_CON_LAST_MODIFIED Fri Mar 11 14:53:05 2022
J 0
(-1985 115);
DISPLAY INVISIBLE (-1985 115);
FORCEPROP 1 LAST CUSTOM_TXT_CDS <CON_LAST_MODIFIED>
J 0
(-1985 115);
DISPLAY 0.978723 (-1985 115);
FORCEPROP 2 LAST CUSTOM_TXT_CDS <XR_PAGE_TITLE>
J 0
(-7990 5350);
DISPLAY 0.638298 (-7990 5350);
PAINT PINK (-7990 5350);
DISPLAY INVISIBLE (-7990 5350);
FORCEPROP 1 LAST CUSTOM_TXT_CDS <NAME_2>
J 0
(-3275 150);
FORCEPROP 1 LAST CUSTOM_TXT_CDS <NAME_1>
J 0
(-3275 275);
FORCEPROP 1 LAST CUSTOM_TXT_CDS <Q_NUMBER>
J 0
(-1503 203);
DISPLAY 1.212766 (-1503 203);
FORCEPROP 1 LAST CUSTOM_TXT_CDS <Q_PROJ>
J 0
(-2482 202);
DISPLAY 1.212766 (-2482 202);
FORCEPROP 1 LAST CUSTOM_TXT_CDS <Q_REV>
J 0
(-284 203);
DISPLAY 1.212766 (-284 203);
FORCEPROP 1 LAST CUSTOM_TXT_CDS <CON_PAGE_NUM> OF <CON_TOTAL_PAGES>
J 0
(-546 118);
DISPLAY 0.978723 (-546 118);
FORCEPROP 1 LAST Q_TITLE DDR5 - CPU1 CHF
J 0
(-9425 150);
DISPLAY 2.446809 (-9425 150);
PAINT GREEN (-9425 150);
FORCEPROP 1 LAST Q_DEPT BU9
J 1
(-3863 149);
DISPLAY 1.957447 (-3863 149);
PAINT GREEN (-3863 149);
FORCEPROP 2 LAST PAGE_BORDER TRUE
J 0
(-7990 5350);
DISPLAY 0.638298 (-7990 5350);
PAINT PINK (-7990 5350);
DISPLAY INVISIBLE (-7990 5350);
FORCEPROP 2 LAST CDS_LIB pure_quanta
J 0
(-100 100);
DISPLAY INVISIBLE (-100 100);
FORCEPROP 1 LAST CDS_LMAN_SYM_OUTLINE -9475,6775,100,-125
J 0
(-100 100);
DISPLAY 0.468085 (-100 100);
PAINT GREEN (-100 100);
DISPLAY INVISIBLE (-100 100);
FORCEPROP 1 LAST COMMENT_BODY TRUE
J 0
(-88 87);
DISPLAY 0.978723 (-88 87);
PAINT GREEN (-88 87);
DISPLAY INVISIBLE (-88 87);
FORCEPROP 2 LAST CDS_XR_PAGE_TITLE CR-102 : @T6G_MB_LIB.T6G(SCH_1):PAGE102
J 0
(-7990 5350);
DISPLAY 0.638298 (-7990 5350);
PAINT PINK (-7990 5350);
DISPLAY INVISIBLE (-7990 5350);
FORCEADD DNS..2
(-8450 2425);
PAINT RED (-8450 2425);
FORCEPROP 2 LAST CDS_LIB mstr_misc
J 0
(-8450 2425);
DISPLAY INVISIBLE (-8450 2425);
FORCEPROP 1 LAST COMMENT_BODY TRUE
R 1
J 0
(-8375 2200);
DISPLAY 0.872340 (-8375 2200);
PAINT PEACH (-8375 2200);
DISPLAY INVISIBLE (-8375 2200);
WIRE 17 -1 (-6075 5550)(-6075 5500);
WIRE 17 -1 (-6075 5575)(-6075 5550);
WIRE 17 -1 (-6075 5500)(-6075 5450);
WIRE 17 -1 (-6075 5450)(-6075 5400);
WIRE 17 -1 (-6075 5575)(-5425 5575);
FORCEPROP 2 LAST SIG_NAME M_F_CPU1_SA_DQ<31:0>
J 0
(-6010 5585);
DISPLAY 0.489362 (-6010 5585);
WIRE 17 -1 (-7875 4150)(-7875 4175);
WIRE 17 -1 (-7875 4150)(-7875 4100);
WIRE 17 -1 (-7875 4175)(-8375 4175);
FORCEPROP 2 LAST SIG_NAME M_F_CPU1_SA_CB<7:0>
J 0
(-8325 4185);
DISPLAY 0.489362 (-8325 4185);
WIRE 17 -1 (-7875 3950)(-7875 4000);
WIRE 17 -1 (-7875 3900)(-7875 3950);
WIRE 17 -1 (-7875 4050)(-7875 4000);
WIRE 17 -1 (-7875 4050)(-7875 4100);
WIRE 17 -1 (-7875 3850)(-7875 3900);
WIRE 17 -1 (-7875 3800)(-7875 3850);
WIRE 17 -1 (-7875 3700)(-7875 3650);
WIRE 17 -1 (-7875 3700)(-7875 3725);
WIRE 17 -1 (-7875 3600)(-7875 3650);
WIRE 17 -1 (-7875 3600)(-7875 3550);
WIRE 17 -1 (-7875 3725)(-8375 3725);
FORCEPROP 2 LAST SIG_NAME M_F_CPU1_SB_CB<7:0>
J 0
(-8325 3735);
DISPLAY 0.489362 (-8325 3735);
WIRE 17 -1 (-7875 5250)(-7875 5300);
WIRE 17 -1 (-7875 5300)(-7875 5350);
WIRE 17 -1 (-7875 5350)(-7875 5400);
WIRE 17 -1 (-7875 5400)(-7875 5450);
WIRE 17 -1 (-7875 5450)(-7875 5500);
WIRE 17 -1 (-7875 5500)(-7875 5550);
WIRE 17 -1 (-7875 5550)(-7875 5575);
WIRE 17 -1 (-7875 5575)(-8375 5575);
FORCEPROP 2 LAST SIG_NAME M_F_CPU1_SA_CA<6:0>
J 0
(-8360 5585);
DISPLAY 0.489362 (-8360 5585);
WIRE 17 -1 (-7875 4850)(-7875 4900);
WIRE 17 -1 (-7875 4900)(-7875 4950);
WIRE 17 -1 (-7875 4950)(-7875 5000);
WIRE 17 -1 (-7875 5000)(-7875 5050);
WIRE 17 -1 (-7875 5050)(-7875 5100);
WIRE 17 -1 (-7875 5100)(-7875 5150);
WIRE 17 -1 (-7875 5150)(-7875 5175);
WIRE 17 -1 (-7875 5175)(-8375 5175);
FORCEPROP 2 LAST SIG_NAME M_F_CPU1_SB_CA<6:0>
J 0
(-8360 5185);
DISPLAY 0.489362 (-8360 5185);
WIRE 17 -1 (-7875 3500)(-7875 3550);
WIRE 17 -1 (-7875 3450)(-7875 3500);
WIRE 17 -1 (-7875 3400)(-7875 3450);
WIRE 17 -1 (-7875 3350)(-7875 3400);
WIRE 17 -1 (-6075 5400)(-6075 5350);
WIRE 17 -1 (-6075 5350)(-6075 5300);
WIRE 17 -1 (-6075 5300)(-6075 5250);
WIRE 17 -1 (-6075 5250)(-6075 5200);
WIRE 17 -1 (-6075 5200)(-6075 5150);
WIRE 17 -1 (-6075 5150)(-6075 5100);
WIRE 17 -1 (-6075 5100)(-6075 5050);
WIRE 17 -1 (-6075 5050)(-6075 5000);
WIRE 17 -1 (-6075 5000)(-6075 4950);
WIRE 17 -1 (-6075 4950)(-6075 4900);
WIRE 17 -1 (-6075 4900)(-6075 4850);
WIRE 17 -1 (-6075 4850)(-6075 4800);
WIRE 17 -1 (-6075 4750)(-6075 4800);
WIRE 17 -1 (-6075 4700)(-6075 4750);
WIRE 17 -1 (-6075 4650)(-6075 4700);
WIRE 17 -1 (-6075 4600)(-6075 4650);
WIRE 17 -1 (-6075 4600)(-6075 4550);
WIRE 17 -1 (-6075 4550)(-6075 4500);
WIRE 17 -1 (-6075 4500)(-6075 4450);
WIRE 17 -1 (-6075 4450)(-6075 4400);
WIRE 17 -1 (-6075 4400)(-6075 4350);
WIRE 17 -1 (-6075 4350)(-6075 4300);
WIRE 17 -1 (-6075 4300)(-6075 4250);
WIRE 17 -1 (-6075 4250)(-6075 4200);
WIRE 17 -1 (-6075 4150)(-6075 4200);
WIRE 17 -1 (-6075 4100)(-6075 4150);
WIRE 17 -1 (-6075 4050)(-6075 4100);
WIRE 17 -1 (-6075 4000)(-6075 4050);
WIRE 17 -1 (-6075 3925)(-6075 3900);
WIRE 17 -1 (-6075 3925)(-5425 3925);
FORCEPROP 2 LAST SIG_NAME M_F_CPU1_SB_DQ<31:0>
J 0
(-6010 3935);
DISPLAY 0.489362 (-6010 3935);
WIRE 17 -1 (-6075 3850)(-6075 3800);
WIRE 17 -1 (-6075 3900)(-6075 3850);
WIRE 17 -1 (-6075 3800)(-6075 3750);
WIRE 17 -1 (-6075 3750)(-6075 3700);
WIRE 17 -1 (-6075 3700)(-6075 3650);
WIRE 17 -1 (-6075 3650)(-6075 3600);
WIRE 17 -1 (-6075 3600)(-6075 3550);
WIRE 17 -1 (-6075 3550)(-6075 3500);
WIRE 17 -1 (-6075 3500)(-6075 3450);
WIRE 17 -1 (-6075 3450)(-6075 3400);
WIRE 17 -1 (-6075 3400)(-6075 3350);
WIRE 17 -1 (-6075 3350)(-6075 3300);
WIRE 17 -1 (-6075 3300)(-6075 3250);
WIRE 17 -1 (-6075 3250)(-6075 3200);
WIRE 17 -1 (-6075 3200)(-6075 3150);
WIRE 17 -1 (-6075 3100)(-6075 3150);
WIRE 17 -1 (-6075 3050)(-6075 3100);
WIRE 17 -1 (-6075 3000)(-6075 3050);
WIRE 17 -1 (-6075 2950)(-6075 3000);
WIRE 17 -1 (-6075 2950)(-6075 2900);
WIRE 17 -1 (-6075 2900)(-6075 2850);
WIRE 17 -1 (-6075 2850)(-6075 2800);
WIRE 17 -1 (-6075 2800)(-6075 2750);
WIRE 17 -1 (-6075 2750)(-6075 2700);
WIRE 17 -1 (-6075 2700)(-6075 2650);
WIRE 17 -1 (-6075 2650)(-6075 2600);
WIRE 17 -1 (-6075 2600)(-6075 2550);
WIRE 17 -1 (-6075 2500)(-6075 2550);
WIRE 17 -1 (-6075 2450)(-6075 2500);
WIRE 17 -1 (-6075 2400)(-6075 2450);
WIRE 17 -1 (-6075 2350)(-6075 2400);
WIRE 17 -1 (-3250 4475)(-3250 4375);
WIRE 17 -1 (-3250 4575)(-3250 4475);
WIRE 17 -1 (-3250 4375)(-3250 4275);
WIRE 17 -1 (-3250 4175)(-3250 4275);
WIRE 17 -1 (-3250 4675)(-3250 4575);
WIRE 17 -1 (-3250 4700)(-3250 4675);
WIRE 17 -1 (-3250 4075)(-3250 4175);
WIRE 17 -1 (-3250 3975)(-3250 4075);
WIRE 17 -1 (-3250 4700)(-2550 4700);
FORCEPROP 2 LAST SIG_NAME M_F_CPU1_SA_DQS_DN<9:0>
J 0
(-3185 4710);
DISPLAY 0.489362 (-3185 4710);
WIRE 17 -1 (-3450 4425)(-3450 4325);
WIRE 17 -1 (-3450 4525)(-3450 4425);
WIRE 17 -1 (-3450 4225)(-3450 4325);
WIRE 17 -1 (-3450 4125)(-3450 4225);
WIRE 17 -1 (-3450 4625)(-3450 4525);
WIRE 17 -1 (-3450 4725)(-3450 4625);
WIRE 17 -1 (-3450 4025)(-3450 4125);
WIRE 17 -1 (-3450 4025)(-3450 3925);
WIRE 17 -1 (-3450 4750)(-3450 4725);
WIRE 17 -1 (-3450 4750)(-2550 4750);
FORCEPROP 2 LAST SIG_NAME M_F_CPU1_SA_DQS_DP<9:0>
J 0
(-3185 4760);
DISPLAY 0.489362 (-3185 4760);
WIRE 17 -1 (-3450 3575)(-3450 3475);
WIRE 17 -1 (-3450 3675)(-3450 3575);
WIRE 17 -1 (-3450 3475)(-3450 3375);
WIRE 17 -1 (-3450 3375)(-3450 3275);
WIRE 17 -1 (-3450 3700)(-3450 3675);
WIRE 17 -1 (-3450 3700)(-2550 3700);
FORCEPROP 2 LAST SIG_NAME M_F_CPU1_SB_DQS_DP<9:0>
J 0
(-3185 3710);
DISPLAY 0.489362 (-3185 3710);
WIRE 17 -1 (-3250 3525)(-3250 3425);
WIRE 17 -1 (-3250 3625)(-3250 3525);
WIRE 17 -1 (-3250 3425)(-3250 3325);
WIRE 17 -1 (-3250 3325)(-3250 3225);
WIRE 17 -1 (-3250 3650)(-3250 3625);
WIRE 17 -1 (-3250 3650)(-2550 3650);
FORCEPROP 2 LAST SIG_NAME M_F_CPU1_SB_DQS_DN<9:0>
J 0
(-3185 3660);
DISPLAY 0.489362 (-3185 3660);
WIRE 17 -1 (-3450 3175)(-3450 3275);
WIRE 17 -1 (-3450 3075)(-3450 3175);
WIRE 17 -1 (-3450 2975)(-3450 3075);
WIRE 17 -1 (-3250 3875)(-3250 3775);
WIRE 17 -1 (-3250 3975)(-3250 3875);
WIRE 17 -1 (-3450 3925)(-3450 3825);
WIRE 17 -1 (-3250 2825)(-3250 2725);
WIRE 17 -1 (-3250 2925)(-3250 2825);
WIRE 17 -1 (-3250 2925)(-3250 3025);
WIRE 17 -1 (-3250 3025)(-3250 3125);
WIRE 17 -1 (-3250 3125)(-3250 3225);
WIRE 17 -1 (-3450 2875)(-3450 2775);
WIRE 17 -1 (-3450 2975)(-3450 2875);
WIRE 16 -1 (-6550 1100)(-6550 1175);
WIRE 16 -1 (-8675 3175)(-8675 3250);
WIRE 16 -1 (-8475 2525)(-8475 2550);
WIRE 16 -1 (-7975 2825)(-8400 2825);
FORCEPROP 2 LAST SIG_NAME I3C_SPD_DDRAF_CPU1_SCL
J 0
(-8460 2835);
DISPLAY 0.489362 (-8460 2835);
WIRE 16 -1 (-7675 2925)(-7675 2825);
FORCEPROP 2 LAST SIG_NAME I3C_SPD_DDRF_CPU1_SCL
J 0
(-8060 2935);
DISPLAY 0.446809 (-8060 2935);
FORCEPROP 2 LASTPROP $XRERR UNIQUE?
J 0
(-8300 2935);
DISPLAY 0.638298 (-8300 2935);
PAINT MONO (-8300 2935);
DISPLAY INVISIBLE (-8300 2935);
WIRE 16 -1 (-7575 2925)(-7675 2925);
WIRE 16 -1 (-7675 2825)(-7775 2825);
WIRE 16 -1 (-8275 2275)(-8475 2275);
WIRE 16 -1 (-8275 2275)(-8275 2675);
WIRE 16 -1 (-8475 2325)(-8475 2275);
WIRE 16 -1 (-8475 2275)(-8500 2275);
WIRE 16 -1 (-7575 2675)(-8275 2675);
FORCEPROP 2 LAST SIG_NAME PWRGD_CHF_CPU1_DIMM
J 0
(-8150 2685);
DISPLAY 0.489362 (-8150 2685);
FORCEPROP 2 LASTPROP $XRERR UNIQUE?
J 0
(-8390 2685);
DISPLAY 0.638298 (-8390 2685);
PAINT MONO (-8390 2685);
DISPLAY INVISIBLE (-8390 2685);
WIRE 16 -1 (-7575 2575)(-8175 2575);
FORCEPROP 2 LAST SIG_NAME TP_CHF_CPU1_DIMM_RFU_6
J 0
(-8185 2585);
DISPLAY 0.489362 (-8185 2585);
FORCEPROP 2 LASTPROP $XRERR UNIQUE?
J 0
(-8415 2575);
DISPLAY 0.638298 (-8415 2575);
PAINT MONO (-8415 2575);
DISPLAY INVISIBLE (-8415 2575);
WIRE 16 -1 (-7575 2975)(-8375 2975);
FORCEPROP 2 LAST SIG_NAME I3C_SPD_DDRAF_CPU1_SDA
J 0
(-8385 2985);
DISPLAY 0.489362 (-8385 2985);
WIRE 16 -1 (-8575 3075)(-7575 3075);
WIRE 16 -1 (-8575 3475)(-8575 3075);
WIRE 16 -1 (-8575 3500)(-8575 3475);
WIRE 16 -1 (-8675 3475)(-8575 3475);
WIRE 16 -1 (-8675 3450)(-8675 3475);
WIRE 16 -1 (-7575 3025)(-8375 3025);
FORCEPROP 2 LAST SIG_NAME PD_CHF_CPU1_DIMM_SAA
J 0
(-8350 3035);
DISPLAY 0.489362 (-8350 3035);
WIRE 16 -1 (-7575 2275)(-8175 2275);
FORCEPROP 2 LAST SIG_NAME TP_CHF_CPU1_DIMM_RFU_0
J 0
(-8185 2285);
DISPLAY 0.489362 (-8185 2285);
FORCEPROP 2 LASTPROP $XRERR UNIQUE?
J 0
(-8415 2275);
DISPLAY 0.638298 (-8415 2275);
PAINT MONO (-8415 2275);
DISPLAY INVISIBLE (-8415 2275);
WIRE 16 -1 (-7575 2075)(-8375 2075);
FORCEPROP 2 LAST SIG_NAME M_F_CPU1_SB_RSP<0>
J 0
(-8325 2085);
DISPLAY 0.489362 (-8325 2085);
WIRE 16 -1 (-7575 2375)(-8175 2375);
FORCEPROP 2 LAST SIG_NAME TP_CHF_CPU1_DIMM_RFU_2
J 0
(-8185 2385);
DISPLAY 0.489362 (-8185 2385);
FORCEPROP 2 LASTPROP $XRERR UNIQUE?
J 0
(-8415 2375);
DISPLAY 0.638298 (-8415 2375);
PAINT MONO (-8415 2375);
DISPLAY INVISIBLE (-8415 2375);
WIRE 16 -1 (-7575 2125)(-8375 2125);
FORCEPROP 2 LAST SIG_NAME M_F_CPU1_SA_RSP<0>
J 0
(-8325 2135);
DISPLAY 0.489362 (-8325 2135);
WIRE 16 -1 (-7575 2475)(-8175 2475);
FORCEPROP 2 LAST SIG_NAME TP_CHF_CPU1_DIMM_RFU_4
J 0
(-8185 2485);
DISPLAY 0.489362 (-8185 2485);
FORCEPROP 2 LASTPROP $XRERR UNIQUE?
J 0
(-8415 2475);
DISPLAY 0.638298 (-8415 2475);
PAINT MONO (-8415 2475);
DISPLAY INVISIBLE (-8415 2475);
WIRE 16 -1 (-7575 2425)(-8175 2425);
FORCEPROP 2 LAST SIG_NAME TP_CHF_CPU1_DIMM_RFU_3
J 0
(-8185 2435);
DISPLAY 0.489362 (-8185 2435);
FORCEPROP 2 LASTPROP $XRERR UNIQUE?
J 0
(-8415 2425);
DISPLAY 0.638298 (-8415 2425);
PAINT MONO (-8415 2425);
DISPLAY INVISIBLE (-8415 2425);
WIRE 16 -1 (-6175 4675)(-6375 4675);
WIRE 16 -1 (-6175 4625)(-6375 4625);
WIRE 16 -1 (-6175 4575)(-6375 4575);
WIRE 16 -1 (-6375 4525)(-6175 4525);
WIRE 16 -1 (-6175 4475)(-6375 4475);
WIRE 16 -1 (-1900 5275)(-2200 5275);
WIRE 16 -1 (-2200 5275)(-2200 5225);
WIRE 16 -1 (-1900 5225)(-2200 5225);
WIRE 16 -1 (-2200 5225)(-2200 5175);
WIRE 16 -1 (-1900 5175)(-2200 5175);
WIRE 16 -1 (-2200 5175)(-2200 5125);
WIRE 16 -1 (-1900 5125)(-2200 5125);
WIRE 16 -1 (-2200 5125)(-2200 5075);
WIRE 16 -1 (-1900 5075)(-2200 5075);
WIRE 16 -1 (-2200 5075)(-2200 5025);
WIRE 16 -1 (-1900 5025)(-2200 5025);
WIRE 16 -1 (-2200 5025)(-2200 4975);
WIRE 16 -1 (-1900 4975)(-2200 4975);
WIRE 16 -1 (-2200 4975)(-2200 4925);
WIRE 16 -1 (-1900 4925)(-2200 4925);
WIRE 16 -1 (-2200 4925)(-2200 4875);
WIRE 16 -1 (-1900 4875)(-2200 4875);
WIRE 16 -1 (-2200 4875)(-2200 4825);
WIRE 16 -1 (-1900 4825)(-2200 4825);
WIRE 16 -1 (-2200 4825)(-2200 4775);
WIRE 16 -1 (-1900 4775)(-2200 4775);
WIRE 16 -1 (-2200 4775)(-2200 4725);
WIRE 16 -1 (-1900 4725)(-2200 4725);
WIRE 16 -1 (-2200 4725)(-2200 4675);
WIRE 16 -1 (-1900 4675)(-2200 4675);
WIRE 16 -1 (-2200 4675)(-2200 4625);
WIRE 16 -1 (-1900 4625)(-2200 4625);
WIRE 16 -1 (-2200 4625)(-2200 4575);
WIRE 16 -1 (-1900 4575)(-2200 4575);
WIRE 16 -1 (-2200 4575)(-2200 4525);
WIRE 16 -1 (-1900 4525)(-2200 4525);
WIRE 16 -1 (-2200 4525)(-2200 4475);
WIRE 16 -1 (-1900 4475)(-2200 4475);
WIRE 16 -1 (-2200 4475)(-2200 4425);
WIRE 16 -1 (-1900 4425)(-2200 4425);
WIRE 16 -1 (-2200 4425)(-2200 4375);
WIRE 16 -1 (-1900 4375)(-2200 4375);
WIRE 16 -1 (-2200 4375)(-2200 4325);
WIRE 16 -1 (-1900 4325)(-2200 4325);
WIRE 16 -1 (-2200 4325)(-2200 4275);
WIRE 16 -1 (-1900 4275)(-2200 4275);
WIRE 16 -1 (-2200 4275)(-2200 4225);
WIRE 16 -1 (-1900 4225)(-2200 4225);
WIRE 16 -1 (-2200 4225)(-2200 4175);
WIRE 16 -1 (-1900 4175)(-2200 4175);
WIRE 16 -1 (-2200 4175)(-2200 4125);
WIRE 16 -1 (-1900 4125)(-2200 4125);
WIRE 16 -1 (-2200 4125)(-2200 4075);
WIRE 16 -1 (-1900 4075)(-2200 4075);
WIRE 16 -1 (-2200 4075)(-2200 4025);
WIRE 16 -1 (-1900 4025)(-2200 4025);
WIRE 16 -1 (-2200 4025)(-2200 3975);
WIRE 16 -1 (-1900 3975)(-2200 3975);
WIRE 16 -1 (-2200 3975)(-2200 3925);
WIRE 16 -1 (-1900 3925)(-2200 3925);
WIRE 16 -1 (-2200 3925)(-2200 3875);
WIRE 16 -1 (-1900 3875)(-2200 3875);
WIRE 16 -1 (-2200 3875)(-2200 3825);
WIRE 16 -1 (-1900 3825)(-2200 3825);
WIRE 16 -1 (-2200 3825)(-2200 3775);
WIRE 16 -1 (-1900 3775)(-2200 3775);
WIRE 16 -1 (-2200 3775)(-2200 3725);
WIRE 16 -1 (-1900 3725)(-2200 3725);
WIRE 16 -1 (-2200 3725)(-2200 3675);
WIRE 16 -1 (-1900 3675)(-2200 3675);
WIRE 16 -1 (-2200 3675)(-2200 3625);
WIRE 16 -1 (-1900 3625)(-2200 3625);
WIRE 16 -1 (-2200 3625)(-2200 3575);
WIRE 16 -1 (-1900 3575)(-2200 3575);
WIRE 16 -1 (-2200 3575)(-2200 3525);
WIRE 16 -1 (-1900 3525)(-2200 3525);
WIRE 16 -1 (-2200 3525)(-2200 3475);
WIRE 16 -1 (-1900 3475)(-2200 3475);
WIRE 16 -1 (-2200 3475)(-2200 3425);
WIRE 16 -1 (-1900 3425)(-2200 3425);
WIRE 16 -1 (-2200 3425)(-2200 3375);
WIRE 16 -1 (-1900 3375)(-2200 3375);
WIRE 16 -1 (-2200 3375)(-2200 3325);
WIRE 16 -1 (-1900 3325)(-2200 3325);
WIRE 16 -1 (-2200 3325)(-2200 3275);
WIRE 16 -1 (-1900 3275)(-2200 3275);
WIRE 16 -1 (-2200 3275)(-2200 3225);
WIRE 16 -1 (-1900 3225)(-2200 3225);
WIRE 16 -1 (-2200 3225)(-2200 3175);
WIRE 16 -1 (-1900 3175)(-2200 3175);
WIRE 16 -1 (-2200 3175)(-2200 3125);
WIRE 16 -1 (-1900 3125)(-2200 3125);
WIRE 16 -1 (-2200 3125)(-2200 3075);
WIRE 16 -1 (-1900 3075)(-2200 3075);
WIRE 16 -1 (-2200 3075)(-2200 3025);
WIRE 16 -1 (-1900 3025)(-2200 3025);
WIRE 16 -1 (-2200 3025)(-2200 2975);
WIRE 16 -1 (-1900 2975)(-2200 2975);
WIRE 16 -1 (-2200 2975)(-2200 2925);
WIRE 16 -1 (-1900 2925)(-2200 2925);
WIRE 16 -1 (-2200 2925)(-2200 2875);
WIRE 16 -1 (-1900 2875)(-2200 2875);
WIRE 16 -1 (-2200 2875)(-2200 2825);
WIRE 16 -1 (-1900 2825)(-2200 2825);
WIRE 16 -1 (-2200 2825)(-2200 2775);
WIRE 16 -1 (-1900 2775)(-2200 2775);
WIRE 16 -1 (-2200 2775)(-2200 2725);
WIRE 16 -1 (-1900 2725)(-2200 2725);
WIRE 16 -1 (-2200 2725)(-2200 2675);
WIRE 16 -1 (-1900 2675)(-2200 2675);
WIRE 16 -1 (-2200 2675)(-2200 2625);
WIRE 16 -1 (-1900 2625)(-2200 2625);
WIRE 16 -1 (-2200 2625)(-2200 2575);
WIRE 16 -1 (-1900 2575)(-2200 2575);
WIRE 16 -1 (-2200 2575)(-2200 2525);
WIRE 16 -1 (-1900 2525)(-2200 2525);
WIRE 16 -1 (-2200 2525)(-2200 2475);
WIRE 16 -1 (-1900 2475)(-2200 2475);
WIRE 16 -1 (-2200 2475)(-2200 2425);
WIRE 16 -1 (-1900 2425)(-2200 2425);
WIRE 16 -1 (-2200 2425)(-2200 2375);
WIRE 16 -1 (-1900 2375)(-2200 2375);
WIRE 16 -1 (-2200 2375)(-2200 2325);
WIRE 16 -1 (-1900 2325)(-2200 2325);
WIRE 16 -1 (-2200 2325)(-2200 2275);
WIRE 16 -1 (-1900 2275)(-2200 2275);
WIRE 16 -1 (-2200 2275)(-2200 2225);
WIRE 16 -1 (-2200 2225)(-2200 2175);
WIRE 16 -1 (-1900 2225)(-2200 2225);
WIRE 16 -1 (-1900 2175)(-2200 2175);
WIRE 16 -1 (-2200 2175)(-2200 2050);
WIRE 16 -1 (-2200 5325)(-1900 5325);
WIRE 16 -1 (-2200 5375)(-2200 5325);
WIRE 16 -1 (-1900 5375)(-2200 5375);
WIRE 16 -1 (-2200 5375)(-2200 5425);
WIRE 16 -1 (-1900 5425)(-2200 5425);
WIRE 16 -1 (-2200 5425)(-2200 6200);
WIRE 16 -1 (-2325 6200)(-2200 6200);
WIRE 16 -1 (-2325 6200)(-2900 6200);
WIRE 16 -1 (-2325 6200)(-2325 6100);
WIRE 16 -1 (-2900 6200)(-2900 6275);
WIRE 16 -1 (-2900 6100)(-2900 6200);
WIRE 16 -1 (-400 2125)(-400 2075);
WIRE 16 -1 (-400 2175)(-400 2125);
WIRE 16 -1 (-400 2125)(-700 2125);
WIRE 16 -1 (-400 2075)(-700 2075);
WIRE 16 -1 (-400 2075)(-400 1825);
WIRE 16 -1 (-400 2275)(-400 2175);
WIRE 16 -1 (-400 2175)(-700 2175);
WIRE 16 -1 (-400 2325)(-400 2275);
WIRE 16 -1 (-400 2275)(-700 2275);
WIRE 16 -1 (-400 2375)(-400 2325);
WIRE 16 -1 (-400 2325)(-700 2325);
WIRE 16 -1 (-400 2425)(-400 2375);
WIRE 16 -1 (-400 2375)(-700 2375);
WIRE 16 -1 (-400 2475)(-400 2425);
WIRE 16 -1 (-400 2425)(-700 2425);
WIRE 16 -1 (-400 2525)(-400 2475);
WIRE 16 -1 (-400 2475)(-700 2475);
WIRE 16 -1 (-400 2575)(-400 2525);
WIRE 16 -1 (-400 2525)(-700 2525);
WIRE 16 -1 (-400 2625)(-400 2575);
WIRE 16 -1 (-400 2575)(-700 2575);
WIRE 16 -1 (-400 2675)(-400 2625);
WIRE 16 -1 (-400 2625)(-700 2625);
WIRE 16 -1 (-400 2725)(-400 2675);
WIRE 16 -1 (-400 2675)(-700 2675);
WIRE 16 -1 (-400 2775)(-400 2725);
WIRE 16 -1 (-400 2725)(-700 2725);
WIRE 16 -1 (-400 2825)(-400 2775);
WIRE 16 -1 (-400 2775)(-700 2775);
WIRE 16 -1 (-400 2875)(-400 2825);
WIRE 16 -1 (-400 2825)(-700 2825);
WIRE 16 -1 (-400 2925)(-400 2875);
WIRE 16 -1 (-400 2875)(-700 2875);
WIRE 16 -1 (-400 2975)(-400 2925);
WIRE 16 -1 (-400 2925)(-700 2925);
WIRE 16 -1 (-400 3025)(-400 2975);
WIRE 16 -1 (-400 2975)(-700 2975);
WIRE 16 -1 (-400 3075)(-400 3025);
WIRE 16 -1 (-400 3025)(-700 3025);
WIRE 16 -1 (-400 3125)(-400 3075);
WIRE 16 -1 (-400 3075)(-700 3075);
WIRE 16 -1 (-400 3175)(-400 3125);
WIRE 16 -1 (-400 3125)(-700 3125);
WIRE 16 -1 (-400 3225)(-400 3175);
WIRE 16 -1 (-400 3175)(-700 3175);
WIRE 16 -1 (-400 3275)(-400 3225);
WIRE 16 -1 (-400 3225)(-700 3225);
WIRE 16 -1 (-400 3325)(-400 3275);
WIRE 16 -1 (-400 3275)(-700 3275);
WIRE 16 -1 (-400 3375)(-400 3325);
WIRE 16 -1 (-400 3325)(-700 3325);
WIRE 16 -1 (-400 3425)(-400 3375);
WIRE 16 -1 (-400 3375)(-700 3375);
WIRE 16 -1 (-400 3475)(-400 3425);
WIRE 16 -1 (-400 3425)(-700 3425);
WIRE 16 -1 (-400 3525)(-400 3475);
WIRE 16 -1 (-400 3475)(-700 3475);
WIRE 16 -1 (-400 3575)(-400 3525);
WIRE 16 -1 (-400 3525)(-700 3525);
WIRE 16 -1 (-400 3625)(-400 3575);
WIRE 16 -1 (-400 3575)(-700 3575);
WIRE 16 -1 (-400 3675)(-400 3625);
WIRE 16 -1 (-400 3625)(-700 3625);
WIRE 16 -1 (-400 3725)(-400 3675);
WIRE 16 -1 (-400 3675)(-700 3675);
WIRE 16 -1 (-400 3775)(-400 3725);
WIRE 16 -1 (-400 3725)(-700 3725);
WIRE 16 -1 (-400 3825)(-400 3775);
WIRE 16 -1 (-400 3775)(-700 3775);
WIRE 16 -1 (-400 3875)(-400 3825);
WIRE 16 -1 (-400 3825)(-700 3825);
WIRE 16 -1 (-400 3925)(-400 3875);
WIRE 16 -1 (-400 3875)(-700 3875);
WIRE 16 -1 (-400 3975)(-400 3925);
WIRE 16 -1 (-400 3925)(-700 3925);
WIRE 16 -1 (-400 4025)(-400 3975);
WIRE 16 -1 (-400 3975)(-700 3975);
WIRE 16 -1 (-400 4075)(-400 4025);
WIRE 16 -1 (-400 4025)(-700 4025);
WIRE 16 -1 (-400 4125)(-400 4075);
WIRE 16 -1 (-400 4075)(-700 4075);
WIRE 16 -1 (-400 4175)(-400 4125);
WIRE 16 -1 (-400 4125)(-700 4125);
WIRE 16 -1 (-400 4225)(-400 4175);
WIRE 16 -1 (-400 4175)(-700 4175);
WIRE 16 -1 (-400 4275)(-400 4225);
WIRE 16 -1 (-400 4225)(-700 4225);
WIRE 16 -1 (-400 4325)(-400 4275);
WIRE 16 -1 (-400 4275)(-700 4275);
WIRE 16 -1 (-400 4375)(-400 4325);
WIRE 16 -1 (-400 4325)(-700 4325);
WIRE 16 -1 (-400 4425)(-400 4375);
WIRE 16 -1 (-400 4375)(-700 4375);
WIRE 16 -1 (-400 4475)(-400 4425);
WIRE 16 -1 (-400 4425)(-700 4425);
WIRE 16 -1 (-400 4525)(-400 4475);
WIRE 16 -1 (-400 4475)(-700 4475);
WIRE 16 -1 (-400 4575)(-400 4525);
WIRE 16 -1 (-400 4525)(-700 4525);
WIRE 16 -1 (-400 4625)(-400 4575);
WIRE 16 -1 (-400 4575)(-700 4575);
WIRE 16 -1 (-400 4675)(-400 4625);
WIRE 16 -1 (-400 4625)(-700 4625);
WIRE 16 -1 (-400 4725)(-400 4675);
WIRE 16 -1 (-400 4675)(-700 4675);
WIRE 16 -1 (-400 4775)(-400 4725);
WIRE 16 -1 (-400 4725)(-700 4725);
WIRE 16 -1 (-400 4825)(-400 4775);
WIRE 16 -1 (-400 4775)(-700 4775);
WIRE 16 -1 (-400 4875)(-400 4825);
WIRE 16 -1 (-400 4825)(-700 4825);
WIRE 16 -1 (-400 4925)(-400 4875);
WIRE 16 -1 (-400 4875)(-700 4875);
WIRE 16 -1 (-400 4975)(-400 4925);
WIRE 16 -1 (-400 4925)(-700 4925);
WIRE 16 -1 (-400 5025)(-400 4975);
WIRE 16 -1 (-400 4975)(-700 4975);
WIRE 16 -1 (-400 5075)(-400 5025);
WIRE 16 -1 (-400 5025)(-700 5025);
WIRE 16 -1 (-400 5125)(-400 5075);
WIRE 16 -1 (-400 5075)(-700 5075);
WIRE 16 -1 (-400 5175)(-400 5125);
WIRE 16 -1 (-400 5125)(-700 5125);
WIRE 16 -1 (-400 5225)(-400 5175);
WIRE 16 -1 (-400 5175)(-700 5175);
WIRE 16 -1 (-400 5275)(-400 5225);
WIRE 16 -1 (-400 5225)(-700 5225);
WIRE 16 -1 (-400 5325)(-400 5275);
WIRE 16 -1 (-400 5275)(-700 5275);
WIRE 16 -1 (-400 5375)(-400 5325);
WIRE 16 -1 (-400 5325)(-700 5325);
WIRE 16 -1 (-400 5425)(-400 5375);
WIRE 16 -1 (-400 5375)(-700 5375);
WIRE 16 -1 (-400 5425)(-700 5425);
WIRE 16 -1 (-6175 4975)(-6375 4975);
WIRE 16 -1 (-6375 4925)(-6175 4925);
WIRE 16 -1 (-6175 4875)(-6375 4875);
WIRE 16 -1 (-3700 3650)(-3550 3650);
WIRE 16 -1 (-3700 3600)(-3350 3600);
WIRE 16 -1 (-3700 4700)(-3550 4700);
WIRE 16 -1 (-3700 4650)(-3350 4650);
WIRE 16 -1 (-3550 4600)(-3700 4600);
WIRE 16 -1 (-3700 4550)(-3350 4550);
WIRE 16 -1 (-3700 3400)(-3350 3400);
WIRE 16 -1 (-3550 4500)(-3700 4500);
WIRE 16 -1 (-3550 3350)(-3700 3350);
WIRE 16 -1 (-3700 3300)(-3350 3300);
WIRE 16 -1 (-3350 4350)(-3700 4350);
WIRE 16 -1 (-3700 3250)(-3550 3250);
WIRE 16 -1 (-3700 3200)(-3350 3200);
WIRE 16 -1 (-3700 4300)(-3550 4300);
WIRE 16 -1 (-3350 4250)(-3700 4250);
WIRE 16 -1 (-3550 3150)(-3700 3150);
WIRE 16 -1 (-3700 3100)(-3350 3100);
WIRE 16 -1 (-3550 4200)(-3700 4200);
WIRE 16 -1 (-3700 4150)(-3350 4150);
WIRE 16 -1 (-3550 3050)(-3700 3050);
WIRE 16 -1 (-3700 3000)(-3350 3000);
WIRE 16 -1 (-3550 4100)(-3700 4100);
WIRE 16 -1 (-3700 4050)(-3350 4050);
WIRE 16 -1 (-3550 2950)(-3700 2950);
WIRE 16 -1 (-3700 2900)(-3350 2900);
WIRE 16 -1 (-3550 4000)(-3700 4000);
WIRE 16 -1 (-3700 3950)(-3350 3950);
WIRE 16 -1 (-3700 2850)(-3550 2850);
WIRE 16 -1 (-3700 2800)(-3350 2800);
WIRE 16 -1 (-3700 3900)(-3550 3900);
WIRE 16 -1 (-3700 3850)(-3350 3850);
WIRE 16 -1 (-3550 2750)(-3700 2750);
WIRE 16 -1 (-3700 2700)(-3350 2700);
WIRE 16 -1 (-3550 3800)(-3700 3800);
WIRE 16 -1 (-3700 3750)(-3350 3750);
WIRE 16 -1 (-3550 3450)(-3700 3450);
WIRE 16 -1 (-3700 3500)(-3350 3500);
WIRE 16 -1 (-3550 3550)(-3700 3550);
WIRE 16 -1 (-3550 4400)(-3700 4400);
WIRE 16 -1 (-3700 4450)(-3350 4450);
WIRE 16 -1 (-7575 2325)(-8175 2325);
FORCEPROP 2 LAST SIG_NAME TP_CHF_CPU1_DIMM_RFU_1
J 0
(-8185 2335);
DISPLAY 0.489362 (-8185 2335);
FORCEPROP 2 LASTPROP $XRERR UNIQUE?
J 0
(-8415 2325);
DISPLAY 0.638298 (-8415 2325);
PAINT MONO (-8415 2325);
DISPLAY INVISIBLE (-8415 2325);
WIRE 16 -1 (-7575 2525)(-8175 2525);
FORCEPROP 2 LAST SIG_NAME TP_CHF_CPU1_DIMM_RFU_5
J 0
(-8185 2535);
DISPLAY 0.489362 (-8185 2535);
FORCEPROP 2 LASTPROP $XRERR UNIQUE?
J 0
(-8415 2525);
DISPLAY 0.638298 (-8415 2525);
PAINT MONO (-8415 2525);
DISPLAY INVISIBLE (-8415 2525);
WIRE 16 -1 (-7575 3225)(-8175 3225);
FORCEPROP 2 LAST SIG_NAME M_F_CPU1_RESET_N
J 0
(-8160 3235);
DISPLAY 0.489362 (-8160 3235);
WIRE 16 -1 (-7575 4675)(-8375 4675);
FORCEPROP 2 LAST SIG_NAME M_F_CPU1_SB_PAR
J 0
(-8325 4685);
DISPLAY 0.489362 (-8325 4685);
WIRE 16 -1 (-7575 4725)(-8375 4725);
FORCEPROP 2 LAST SIG_NAME M_F_CPU1_SA_PAR
J 0
(-8325 4735);
DISPLAY 0.489362 (-8325 4735);
WIRE 16 -1 (-6175 2325)(-6375 2325);
WIRE 16 -1 (-6175 2375)(-6375 2375);
WIRE 16 -1 (-6175 2425)(-6375 2425);
WIRE 16 -1 (-6375 2475)(-6175 2475);
WIRE 16 -1 (-6175 2525)(-6375 2525);
WIRE 16 -1 (-6175 2575)(-6375 2575);
WIRE 16 -1 (-6175 2625)(-6375 2625);
WIRE 16 -1 (-6375 2675)(-6175 2675);
WIRE 16 -1 (-6175 2725)(-6375 2725);
WIRE 16 -1 (-6175 2775)(-6375 2775);
WIRE 16 -1 (-6175 2825)(-6375 2825);
WIRE 16 -1 (-6375 2875)(-6175 2875);
WIRE 16 -1 (-6175 2925)(-6375 2925);
WIRE 16 -1 (-6175 2975)(-6375 2975);
WIRE 16 -1 (-6175 3025)(-6375 3025);
WIRE 16 -1 (-6375 3075)(-6175 3075);
WIRE 16 -1 (-6175 3125)(-6375 3125);
WIRE 16 -1 (-6175 3175)(-6375 3175);
WIRE 16 -1 (-6175 3225)(-6375 3225);
WIRE 16 -1 (-6375 3275)(-6175 3275);
WIRE 16 -1 (-6175 3325)(-6375 3325);
WIRE 16 -1 (-6175 3375)(-6375 3375);
WIRE 16 -1 (-6175 3425)(-6375 3425);
WIRE 16 -1 (-6375 3475)(-6175 3475);
WIRE 16 -1 (-6175 3525)(-6375 3525);
WIRE 16 -1 (-6175 3575)(-6375 3575);
WIRE 16 -1 (-6175 3625)(-6375 3625);
WIRE 16 -1 (-6375 3675)(-6175 3675);
WIRE 16 -1 (-6175 3725)(-6375 3725);
WIRE 16 -1 (-6175 3775)(-6375 3775);
WIRE 16 -1 (-6175 3825)(-6375 3825);
WIRE 16 -1 (-6375 3875)(-6175 3875);
WIRE 16 -1 (-6175 3975)(-6375 3975);
WIRE 16 -1 (-6175 4025)(-6375 4025);
WIRE 16 -1 (-6175 4075)(-6375 4075);
WIRE 16 -1 (-6375 4125)(-6175 4125);
WIRE 16 -1 (-6175 4175)(-6375 4175);
WIRE 16 -1 (-6175 4225)(-6375 4225);
WIRE 16 -1 (-6175 4275)(-6375 4275);
WIRE 16 -1 (-6375 4325)(-6175 4325);
WIRE 16 -1 (-6175 4375)(-6375 4375);
WIRE 16 -1 (-6175 4425)(-6375 4425);
WIRE 16 -1 (-6375 4725)(-6175 4725);
WIRE 16 -1 (-6175 4775)(-6375 4775);
WIRE 16 -1 (-6175 4825)(-6375 4825);
WIRE 16 -1 (-6175 5025)(-6375 5025);
WIRE 16 -1 (-6175 5075)(-6375 5075);
WIRE 16 -1 (-6375 5125)(-6175 5125);
WIRE 16 -1 (-6175 5175)(-6375 5175);
WIRE 16 -1 (-6175 5225)(-6375 5225);
WIRE 16 -1 (-6175 5275)(-6375 5275);
WIRE 16 -1 (-6375 5325)(-6175 5325);
WIRE 16 -1 (-6175 5375)(-6375 5375);
WIRE 16 -1 (-6175 5425)(-6375 5425);
WIRE 16 -1 (-6175 5475)(-6375 5475);
WIRE 16 -1 (-7575 4425)(-8375 4425);
FORCEPROP 2 LAST SIG_NAME M_F_CPU1_SB_CS_N<1>
J 0
(-8325 4435);
DISPLAY 0.489362 (-8325 4435);
WIRE 16 -1 (-7575 4575)(-8375 4575);
FORCEPROP 2 LAST SIG_NAME M_F_CPU1_SA_CS_N<1>
J 0
(-8325 4585);
DISPLAY 0.489362 (-8325 4585);
WIRE 16 -1 (-7575 4375)(-8375 4375);
FORCEPROP 2 LAST SIG_NAME M_F_CPU1_SB_CS_N<0>
J 0
(-8325 4385);
DISPLAY 0.489362 (-8325 4385);
WIRE 16 -1 (-7575 4525)(-8375 4525);
FORCEPROP 2 LAST SIG_NAME M_F_CPU1_SA_CS_N<0>
J 0
(-8325 4535);
DISPLAY 0.489362 (-8325 4535);
WIRE 16 -1 (-7575 4275)(-8375 4275);
FORCEPROP 2 LAST SIG_NAME M_F_CPU1_CLK_DP<0>
J 0
(-8325 4285);
DISPLAY 0.489362 (-8325 4285);
WIRE 16 -1 (-7575 4225)(-8375 4225);
FORCEPROP 2 LAST SIG_NAME M_F_CPU1_CLK_DN<0>
J 0
(-8325 4235);
DISPLAY 0.489362 (-8325 4235);
WIRE 16 -1 (-7575 3325)(-7775 3325);
WIRE 16 -1 (-7575 3375)(-7775 3375);
WIRE 16 -1 (-7575 3425)(-7775 3425);
WIRE 16 -1 (-7575 3475)(-7775 3475);
WIRE 16 -1 (-7575 3525)(-7775 3525);
WIRE 16 -1 (-7575 3575)(-7775 3575);
WIRE 16 -1 (-7575 3625)(-7775 3625);
WIRE 16 -1 (-7575 3775)(-7775 3775);
WIRE 16 -1 (-7575 3875)(-7775 3875);
WIRE 16 -1 (-7575 3925)(-7775 3925);
WIRE 16 -1 (-7575 4025)(-7775 4025);
WIRE 16 -1 (-7575 4075)(-7775 4075);
WIRE 16 -1 (-7575 5125)(-7775 5125);
WIRE 16 -1 (-7575 5525)(-7775 5525);
WIRE 16 -1 (-7575 5075)(-7775 5075);
WIRE 16 -1 (-7575 5475)(-7775 5475);
WIRE 16 -1 (-7575 5025)(-7775 5025);
WIRE 16 -1 (-7575 5425)(-7775 5425);
WIRE 16 -1 (-7575 4975)(-7775 4975);
WIRE 16 -1 (-7575 5375)(-7775 5375);
WIRE 16 -1 (-7575 4925)(-7775 4925);
WIRE 16 -1 (-7575 5325)(-7775 5325);
WIRE 16 -1 (-7575 4875)(-7775 4875);
WIRE 16 -1 (-7575 5275)(-7775 5275);
WIRE 16 -1 (-7575 4825)(-7775 4825);
WIRE 16 -1 (-7575 5225)(-7775 5225);
WIRE 16 -1 (-7575 3175)(-8175 3175);
FORCEPROP 2 LAST SIG_NAME M_F_CPU1_ALERT_N
J 0
(-8160 3185);
DISPLAY 0.489362 (-8160 3185);
WIRE 16 -1 (-7575 3675)(-7775 3675);
WIRE 16 -1 (-7575 3825)(-7775 3825);
WIRE 16 -1 (-7575 3975)(-7775 3975);
WIRE 16 -1 (-7575 4125)(-7775 4125);
WIRE 16 -1 (-6375 5525)(-6175 5525);
WIRE 16 -1 (-2325 5775)(-2900 5775);
WIRE 16 -1 (-2325 5775)(-2325 5900);
WIRE 16 -1 (-2900 5775)(-2900 5900);
WIRE 16 -1 (-2900 5775)(-2900 5700);
WIRE 16 -1 (-9050 2275)(-8700 2275);
FORCEPROP 2 LAST SIG_NAME PWRGD_CHAF_CPU1
J 0
(-9035 2285);
DISPLAY 0.489362 (-9035 2285);
WIRE 16 -1 (-6550 1450)(-6550 1375);
WIRE 16 -1 (-6550 1450)(-7275 1450);
FORCEPROP 2 LAST SIG_NAME PD_CHF_CPU1_DIMM_SAA
J 0
(-7260 1460);
DISPLAY 0.489362 (-7260 1460);
DOT 1 (-2325 6200);
DOT 1 (-2900 6200);
DOT 1 (-2900 5775);
DOT 1 (-8475 2275);
DOT 1 (-8575 3475);
DOT 1 (-2200 2175);
DOT 1 (-2200 2225);
DOT 1 (-2200 2275);
DOT 1 (-2200 2325);
DOT 1 (-2200 2375);
DOT 1 (-2200 2475);
DOT 1 (-2200 2425);
DOT 1 (-2200 2525);
DOT 1 (-2200 2575);
DOT 1 (-2200 2625);
DOT 1 (-2200 2725);
DOT 1 (-2200 2675);
DOT 1 (-2200 2775);
DOT 1 (-2200 2825);
DOT 1 (-2200 2875);
DOT 1 (-2200 2925);
DOT 1 (-2200 2975);
DOT 1 (-2200 3025);
DOT 1 (-2200 3075);
DOT 1 (-2200 3125);
DOT 1 (-2200 3175);
DOT 1 (-2200 3225);
DOT 1 (-2200 3275);
DOT 1 (-2200 3325);
DOT 1 (-2200 3375);
DOT 1 (-2200 3425);
DOT 1 (-2200 3475);
DOT 1 (-2200 3525);
DOT 1 (-2200 3575);
DOT 1 (-2200 3625);
DOT 1 (-2200 3675);
DOT 1 (-2200 3725);
DOT 1 (-2200 3775);
DOT 1 (-2200 3825);
DOT 1 (-2200 3875);
DOT 1 (-400 2075);
DOT 1 (-400 2125);
DOT 1 (-400 2175);
DOT 1 (-400 2275);
DOT 1 (-400 2325);
DOT 1 (-400 2375);
DOT 1 (-400 2425);
DOT 1 (-400 2475);
DOT 1 (-400 2525);
DOT 1 (-400 2575);
DOT 1 (-400 2625);
DOT 1 (-400 2725);
DOT 1 (-400 2675);
DOT 1 (-400 2775);
DOT 1 (-400 2825);
DOT 1 (-400 2875);
DOT 1 (-400 2925);
DOT 1 (-400 2975);
DOT 1 (-400 3025);
DOT 1 (-400 3075);
DOT 1 (-400 3125);
DOT 1 (-400 3175);
DOT 1 (-400 3225);
DOT 1 (-400 3275);
DOT 1 (-400 3375);
DOT 1 (-400 3325);
DOT 1 (-400 3425);
DOT 1 (-400 3475);
DOT 1 (-400 3525);
DOT 1 (-400 3625);
DOT 1 (-400 3575);
DOT 1 (-400 3675);
DOT 1 (-400 3725);
DOT 1 (-400 3775);
DOT 1 (-400 3875);
DOT 1 (-400 3825);
DOT 1 (-2200 3925);
DOT 1 (-400 3925);
DOT 1 (-2200 3975);
DOT 1 (-2200 4025);
DOT 1 (-2200 4075);
DOT 1 (-2200 4125);
DOT 1 (-2200 4175);
DOT 1 (-2200 4225);
DOT 1 (-2200 4275);
DOT 1 (-2200 4325);
DOT 1 (-2200 4375);
DOT 1 (-2200 4475);
DOT 1 (-2200 4525);
DOT 1 (-2200 4575);
DOT 1 (-2200 4625);
DOT 1 (-2200 4675);
DOT 1 (-2200 4725);
DOT 1 (-2200 4775);
DOT 1 (-2200 4825);
DOT 1 (-2200 4875);
DOT 1 (-2200 4925);
DOT 1 (-2200 4975);
DOT 1 (-2200 5025);
DOT 1 (-2200 5075);
DOT 1 (-2200 5125);
DOT 1 (-2200 5175);
DOT 1 (-2200 5375);
DOT 1 (-400 3975);
DOT 1 (-400 4025);
DOT 1 (-400 4075);
DOT 1 (-400 4125);
DOT 1 (-400 4175);
DOT 1 (-400 4225);
DOT 1 (-400 4275);
DOT 1 (-400 4325);
DOT 1 (-400 4375);
DOT 1 (-400 4425);
DOT 1 (-400 4475);
DOT 1 (-400 4525);
DOT 1 (-400 4575);
DOT 1 (-400 4625);
DOT 1 (-400 4675);
DOT 1 (-400 4725);
DOT 1 (-400 4775);
DOT 1 (-400 4825);
DOT 1 (-400 4875);
DOT 1 (-400 4925);
DOT 1 (-400 4975);
DOT 1 (-400 5025);
DOT 1 (-400 5075);
DOT 1 (-400 5125);
DOT 1 (-400 5175);
DOT 1 (-400 5225);
DOT 1 (-400 5275);
DOT 1 (-400 5325);
DOT 1 (-400 5375);
DOT 1 (-2200 4425);
DOT 1 (-2200 5425);
DOT 1 (-2200 5225);
QUIT
